FILE_TYPE = MACRO_DRAWING;
SET COLOR_WIRE YELLOW;
SET COLOR_PROP ORANGE;
SET COLOR_DOT WHITE;
SET COLOR_ARC YELLOW;
SET COLOR_BODY GREEN;
SET COLOR_NOTE PURPLE;
SET PROP_DISPLAY VALUE;
SET PAGE_NUMBER P21;
SET PATH_NUMBER P182;
FORCEADD OFFPAGE..1
(-2750 1950);
FORCEPROP 2 LAST $XR0 13 
J 0
(-2971 1950);
DISPLAY 0.638298 (-2971 1950);
PAINT MONO (-2971 1950);
FORCEPROP 2 LAST $XR1 21 
J 0
(-3061 1950);
DISPLAY 0.638298 (-3061 1950);
PAINT MONO (-3061 1950);
FORCEPROP 2 LAST PATH I1
J 0
(-2950 2000);
DISPLAY 0.680851 (-2950 2000);
DISPLAY INVISIBLE (-2950 2000);
FORCEPROP 2 LAST CDS_LIB standard
J 0
(-2750 1950);
DISPLAY INVISIBLE (-2750 1950);
FORCEPROP 1 LAST OFFPAGE TRUE
J 0
(-2425 1825);
DISPLAY 0.872340 (-2425 1825);
PAINT GREEN (-2425 1825);
DISPLAY INVISIBLE (-2425 1825);
FORCEPROP 1 LAST COMMENT_BODY TRUE
J 0
(-2625 1850);
DISPLAY 0.872340 (-2625 1850);
PAINT PEACH (-2625 1850);
DISPLAY INVISIBLE (-2625 1850);
FORCEADD Q_RES..1
(175 2150);
FORCEPROP 1 LAST MATERIAL EMPTY
J 0
(325 2150);
DISPLAY 0.510638 (325 2150);
PAINT RED (325 2150);
FORCEPROP 1 LAST VALUE 33.2
J 2
(550 2150);
DISPLAY 0.510638 (550 2150);
PAINT SKYBLUE (550 2150);
FORCEPROP 1 LAST PATH I100
J 0
(125 2300);
DISPLAY 0.978723 (125 2300);
PAINT WHITE (125 2300);
DISPLAY INVISIBLE (125 2300);
FORCEPROP 1 LAST PACK_TYPE 0402LF
J 0
(425 2000);
DISPLAY 0.510638 (425 2000);
PAINT SKYBLUE (425 2000);
DISPLAY INVISIBLE (425 2000);
FORCEPROP 1 LAST WATTAGE 1/16W
J 2
(200 1950);
DISPLAY 0.510638 (200 1950);
PAINT SKYBLUE (200 1950);
DISPLAY INVISIBLE (200 1950);
FORCEPROP 2 LAST CDS_LIB pure_quanta
J 0
(175 2150);
DISPLAY INVISIBLE (175 2150);
FORCEPROP 1 LAST TOLERANCE 1%
J 0
(175 2050);
DISPLAY 0.510638 (175 2050);
PAINT SKYBLUE (175 2050);
DISPLAY INVISIBLE (175 2050);
FORCEPROP 1 LAST PART_NUMBER CS03322FB03
J 0
(-25 2625);
DISPLAY 0.510638 (-25 2625);
PAINT WHITE (-25 2625);
DISPLAY INVISIBLE (-25 2625);
FORCEPROP 1 LAST LOCATION R653
J 0
(-50 2150);
DISPLAY 0.702128 (-50 2150);
PAINT YELLOW (-50 2150);
FORCEPROP 1 LASTPIN (75 2150) $PN 1
J 0
(87 2162);
DISPLAY 0.808511 (87 2162);
PAINT WHITE (87 2162);
FORCEPROP 1 LASTPIN (275 2150) $PN 2
J 0
(237 2162);
DISPLAY 0.808511 (237 2162);
PAINT WHITE (237 2162);
FORCEPROP 0 LAST $SEC 1
J 0
(750 2200);
DISPLAY 0.680851 (750 2200);
PAINT MONO (750 2200);
DISPLAY INVISIBLE (750 2200);
FORCEPROP 0 LAST CDS_SEC 1
J 0
(650 2200);
DISPLAY 1.021277 (650 2200);
DISPLAY INVISIBLE (650 2200);
FORCEADD Q_RES..1
(175 2200);
FORCEPROP 1 LAST MATERIAL EMPTY
J 0
(325 2200);
DISPLAY 0.510638 (325 2200);
PAINT RED (325 2200);
FORCEPROP 1 LAST VALUE 33.2
J 2
(550 2200);
DISPLAY 0.510638 (550 2200);
PAINT SKYBLUE (550 2200);
FORCEPROP 1 LAST PATH I101
J 0
(125 2350);
DISPLAY 0.978723 (125 2350);
PAINT WHITE (125 2350);
DISPLAY INVISIBLE (125 2350);
FORCEPROP 1 LAST PACK_TYPE 0402LF
J 0
(425 2050);
DISPLAY 0.510638 (425 2050);
PAINT SKYBLUE (425 2050);
DISPLAY INVISIBLE (425 2050);
FORCEPROP 1 LAST WATTAGE 1/16W
J 2
(150 2050);
DISPLAY 0.510638 (150 2050);
PAINT SKYBLUE (150 2050);
DISPLAY INVISIBLE (150 2050);
FORCEPROP 2 LAST CDS_LIB pure_quanta
J 0
(175 2200);
DISPLAY INVISIBLE (175 2200);
FORCEPROP 1 LAST TOLERANCE 1%
J 0
(175 2100);
DISPLAY 0.510638 (175 2100);
PAINT SKYBLUE (175 2100);
DISPLAY INVISIBLE (175 2100);
FORCEPROP 1 LAST PART_NUMBER CS03322FB03
J 0
(-50 2625);
DISPLAY 0.510638 (-50 2625);
PAINT WHITE (-50 2625);
DISPLAY INVISIBLE (-50 2625);
FORCEPROP 1 LAST LOCATION R652
J 0
(-50 2200);
DISPLAY 0.702128 (-50 2200);
PAINT YELLOW (-50 2200);
FORCEPROP 1 LASTPIN (75 2200) $PN 1
J 0
(87 2212);
DISPLAY 0.808511 (87 2212);
PAINT WHITE (87 2212);
FORCEPROP 1 LASTPIN (275 2200) $PN 2
J 0
(237 2212);
DISPLAY 0.808511 (237 2212);
PAINT WHITE (237 2212);
FORCEPROP 0 LAST $SEC 1
J 0
(750 2250);
DISPLAY 0.680851 (750 2250);
PAINT MONO (750 2250);
DISPLAY INVISIBLE (750 2250);
FORCEPROP 0 LAST CDS_SEC 1
J 0
(650 2250);
DISPLAY 1.021277 (650 2250);
DISPLAY INVISIBLE (650 2250);
FORCEADD OFFPAGE..3
R 2
(-650 2300);
FORCEPROP 2 LAST $XR0 12 
J 0
(-929 2300);
DISPLAY 0.638298 (-929 2300);
PAINT MONO (-929 2300);
FORCEPROP 2 LAST CDS_LIB standard
J 0
(-650 2300);
DISPLAY INVISIBLE (-650 2300);
FORCEPROP 1 LAST OFFPAGE TRUE
J 2
(-975 2175);
DISPLAY 0.872340 (-975 2175);
PAINT GREEN (-975 2175);
DISPLAY INVISIBLE (-975 2175);
FORCEPROP 1 LAST COMMENT_BODY TRUE
J 2
(-600 2200);
DISPLAY 0.872340 (-600 2200);
PAINT PEACH (-600 2200);
DISPLAY INVISIBLE (-600 2200);
FORCEPROP 2 LAST PATH I108
J 0
(-925 2350);
DISPLAY 0.680851 (-925 2350);
DISPLAY INVISIBLE (-925 2350);
FORCEADD OFFPAGE..3
R 2
(-650 2250);
FORCEPROP 2 LAST $XR0 12 
J 0
(-929 2250);
DISPLAY 0.638298 (-929 2250);
PAINT MONO (-929 2250);
FORCEPROP 2 LAST CDS_LIB standard
J 0
(-650 2250);
DISPLAY INVISIBLE (-650 2250);
FORCEPROP 1 LAST OFFPAGE TRUE
J 2
(-975 2125);
DISPLAY 0.872340 (-975 2125);
PAINT GREEN (-975 2125);
DISPLAY INVISIBLE (-975 2125);
FORCEPROP 1 LAST COMMENT_BODY TRUE
J 2
(-600 2150);
DISPLAY 0.872340 (-600 2150);
PAINT PEACH (-600 2150);
DISPLAY INVISIBLE (-600 2150);
FORCEPROP 2 LAST PATH I109
J 0
(-925 2300);
DISPLAY 0.680851 (-925 2300);
DISPLAY INVISIBLE (-925 2300);
FORCEADD OFFPAGE..3
R 2
(-650 2150);
FORCEPROP 2 LAST $XR0 12 
J 0
(-929 2150);
DISPLAY 0.638298 (-929 2150);
PAINT MONO (-929 2150);
FORCEPROP 2 LAST CDS_LIB standard
J 0
(-650 2150);
DISPLAY INVISIBLE (-650 2150);
FORCEPROP 1 LAST OFFPAGE TRUE
J 2
(-975 2025);
DISPLAY 0.872340 (-975 2025);
PAINT GREEN (-975 2025);
DISPLAY INVISIBLE (-975 2025);
FORCEPROP 1 LAST COMMENT_BODY TRUE
J 2
(-600 2050);
DISPLAY 0.872340 (-600 2050);
PAINT PEACH (-600 2050);
DISPLAY INVISIBLE (-600 2050);
FORCEPROP 2 LAST PATH I110
J 0
(-925 2200);
DISPLAY 0.680851 (-925 2200);
DISPLAY INVISIBLE (-925 2200);
FORCEADD OFFPAGE..3
R 2
(-650 2200);
FORCEPROP 2 LAST $XR0 12 
J 0
(-929 2200);
DISPLAY 0.638298 (-929 2200);
PAINT MONO (-929 2200);
FORCEPROP 2 LAST CDS_LIB standard
J 0
(-650 2200);
DISPLAY INVISIBLE (-650 2200);
FORCEPROP 1 LAST OFFPAGE TRUE
J 2
(-975 2075);
DISPLAY 0.872340 (-975 2075);
PAINT GREEN (-975 2075);
DISPLAY INVISIBLE (-975 2075);
FORCEPROP 1 LAST COMMENT_BODY TRUE
J 2
(-600 2100);
DISPLAY 0.872340 (-600 2100);
PAINT PEACH (-600 2100);
DISPLAY INVISIBLE (-600 2100);
FORCEPROP 2 LAST PATH I111
J 0
(-925 2250);
DISPLAY 0.680851 (-925 2250);
DISPLAY INVISIBLE (-925 2250);
FORCEADD UNIVERSAL_POWER..1
(975 4000);
FORCEPROP 3 LASTPIN (975 3950) SIG_NAME P3V3_AUX\g
J 0
(985 3960);
DISPLAY 0.659574 (985 3960);
PAINT MONO (985 3960);
DISPLAY INVISIBLE (985 3960);
FORCEPROP 1 LAST HDL_POWER P3V3_AUX
J 1
(975 4050);
DISPLAY 0.702128 (975 4050);
PAINT GREEN (975 4050);
FORCEPROP 1 LAST PATH I112
J 0
(1025 4025);
DISPLAY 0.872340 (1025 4025);
PAINT AQUA (1025 4025);
DISPLAY INVISIBLE (1025 4025);
FORCEPROP 2 LAST CDS_LIB logical_power
J 0
(975 4000);
DISPLAY INVISIBLE (975 4000);
FORCEADD OFFPAGE..3
R 6
(4325 2100);
FORCEPROP 2 LAST $XR0 12 
J 0
(4539 2100);
DISPLAY 0.638298 (4539 2100);
PAINT MONO (4539 2100);
FORCEPROP 2 LAST PATH I113
R 2
J 0
(4600 2050);
DISPLAY 0.680851 (4600 2050);
DISPLAY INVISIBLE (4600 2050);
FORCEPROP 1 LAST COMMENT_BODY TRUE
R 2
J 2
(4275 2200);
DISPLAY 0.872340 (4275 2200);
PAINT PEACH (4275 2200);
DISPLAY INVISIBLE (4275 2200);
FORCEPROP 1 LAST OFFPAGE TRUE
R 2
J 2
(4650 2225);
DISPLAY 0.872340 (4650 2225);
PAINT GREEN (4650 2225);
DISPLAY INVISIBLE (4650 2225);
FORCEPROP 2 LAST CDS_LIB standard
R 2
J 0
(4325 2100);
DISPLAY INVISIBLE (4325 2100);
FORCEADD OFFPAGE..3
R 6
(4325 1850);
FORCEPROP 2 LAST $XR0 12 
J 0
(4539 1850);
DISPLAY 0.638298 (4539 1850);
PAINT MONO (4539 1850);
FORCEPROP 2 LAST PATH I114
R 2
J 0
(4600 1800);
DISPLAY 0.680851 (4600 1800);
DISPLAY INVISIBLE (4600 1800);
FORCEPROP 1 LAST COMMENT_BODY TRUE
R 2
J 2
(4275 1950);
DISPLAY 0.872340 (4275 1950);
PAINT PEACH (4275 1950);
DISPLAY INVISIBLE (4275 1950);
FORCEPROP 1 LAST OFFPAGE TRUE
R 2
J 2
(4650 1975);
DISPLAY 0.872340 (4650 1975);
PAINT GREEN (4650 1975);
DISPLAY INVISIBLE (4650 1975);
FORCEPROP 2 LAST CDS_LIB standard
R 2
J 0
(4325 1850);
DISPLAY INVISIBLE (4325 1850);
FORCEADD OFFPAGE..3
R 6
(4325 2000);
FORCEPROP 2 LAST $XR0 12 
J 0
(4539 2000);
DISPLAY 0.638298 (4539 2000);
PAINT MONO (4539 2000);
FORCEPROP 2 LAST PATH I115
R 2
J 0
(4600 1950);
DISPLAY 0.680851 (4600 1950);
DISPLAY INVISIBLE (4600 1950);
FORCEPROP 1 LAST COMMENT_BODY TRUE
R 2
J 2
(4275 2100);
DISPLAY 0.872340 (4275 2100);
PAINT PEACH (4275 2100);
DISPLAY INVISIBLE (4275 2100);
FORCEPROP 1 LAST OFFPAGE TRUE
R 2
J 2
(4650 2125);
DISPLAY 0.872340 (4650 2125);
PAINT GREEN (4650 2125);
DISPLAY INVISIBLE (4650 2125);
FORCEPROP 2 LAST CDS_LIB standard
R 2
J 0
(4325 2000);
DISPLAY INVISIBLE (4325 2000);
FORCEADD OFFPAGE..3
R 6
(4325 1950);
FORCEPROP 2 LAST $XR0 12 
J 0
(4539 1950);
DISPLAY 0.638298 (4539 1950);
PAINT MONO (4539 1950);
FORCEPROP 2 LAST CDS_LIB standard
R 2
J 0
(4325 1950);
DISPLAY INVISIBLE (4325 1950);
FORCEPROP 1 LAST OFFPAGE TRUE
R 2
J 2
(4650 2075);
DISPLAY 0.872340 (4650 2075);
PAINT GREEN (4650 2075);
DISPLAY INVISIBLE (4650 2075);
FORCEPROP 1 LAST COMMENT_BODY TRUE
R 2
J 2
(4275 2050);
DISPLAY 0.872340 (4275 2050);
PAINT PEACH (4275 2050);
DISPLAY INVISIBLE (4275 2050);
FORCEPROP 2 LAST PATH I116
R 2
J 0
(4600 1900);
DISPLAY 0.680851 (4600 1900);
DISPLAY INVISIBLE (4600 1900);
FORCEADD OFFPAGE..1
(2425 1300);
FORCEPROP 2 LAST $XR0 21 
J 0
(2204 1300);
DISPLAY 0.638298 (2204 1300);
PAINT MONO (2204 1300);
FORCEPROP 2 LAST CDS_LIB standard
J 0
(2425 1300);
DISPLAY INVISIBLE (2425 1300);
FORCEPROP 1 LAST OFFPAGE TRUE
J 0
(2750 1175);
DISPLAY 0.872340 (2750 1175);
PAINT GREEN (2750 1175);
DISPLAY INVISIBLE (2750 1175);
FORCEPROP 1 LAST COMMENT_BODY TRUE
J 0
(2550 1200);
DISPLAY 0.872340 (2550 1200);
PAINT PEACH (2550 1200);
DISPLAY INVISIBLE (2550 1200);
FORCEPROP 2 LAST PATH I117
J 0
(2225 1350);
DISPLAY 0.680851 (2225 1350);
DISPLAY INVISIBLE (2225 1350);
FORCEADD OFFPAGE..1
(2425 1350);
FORCEPROP 2 LAST $XR0 21 
J 0
(2204 1350);
DISPLAY 0.638298 (2204 1350);
PAINT MONO (2204 1350);
FORCEPROP 2 LAST CDS_LIB standard
J 0
(2425 1350);
DISPLAY INVISIBLE (2425 1350);
FORCEPROP 1 LAST OFFPAGE TRUE
J 0
(2750 1225);
DISPLAY 0.872340 (2750 1225);
PAINT GREEN (2750 1225);
DISPLAY INVISIBLE (2750 1225);
FORCEPROP 1 LAST COMMENT_BODY TRUE
J 0
(2550 1250);
DISPLAY 0.872340 (2550 1250);
PAINT PEACH (2550 1250);
DISPLAY INVISIBLE (2550 1250);
FORCEPROP 2 LAST PATH I118
J 0
(2225 1400);
DISPLAY 0.680851 (2225 1400);
DISPLAY INVISIBLE (2225 1400);
FORCEADD OFFPAGE..1
(2425 1400);
FORCEPROP 2 LAST $XR0 21 
J 0
(2204 1400);
DISPLAY 0.638298 (2204 1400);
PAINT MONO (2204 1400);
FORCEPROP 2 LAST PATH I119
J 0
(2225 1450);
DISPLAY 0.680851 (2225 1450);
DISPLAY INVISIBLE (2225 1450);
FORCEPROP 1 LAST COMMENT_BODY TRUE
J 0
(2550 1300);
DISPLAY 0.702128 (2550 1300);
PAINT PEACH (2550 1300);
DISPLAY INVISIBLE (2550 1300);
FORCEPROP 1 LAST OFFPAGE TRUE
J 0
(2750 1275);
DISPLAY 0.872340 (2750 1275);
PAINT GREEN (2750 1275);
DISPLAY INVISIBLE (2750 1275);
FORCEPROP 2 LAST CDS_LIB standard
J 0
(2425 1400);
DISPLAY INVISIBLE (2425 1400);
FORCEADD OFFPAGE..1
(2425 1450);
FORCEPROP 2 LAST $XR0 21 
J 0
(2204 1450);
DISPLAY 0.638298 (2204 1450);
PAINT MONO (2204 1450);
FORCEPROP 2 LAST PATH I120
J 0
(2225 1500);
DISPLAY 0.680851 (2225 1500);
DISPLAY INVISIBLE (2225 1500);
FORCEPROP 1 LAST COMMENT_BODY TRUE
J 0
(2550 1350);
DISPLAY 0.872340 (2550 1350);
PAINT PEACH (2550 1350);
DISPLAY INVISIBLE (2550 1350);
FORCEPROP 1 LAST OFFPAGE TRUE
J 0
(2750 1325);
DISPLAY 0.872340 (2750 1325);
PAINT GREEN (2750 1325);
DISPLAY INVISIBLE (2750 1325);
FORCEPROP 2 LAST CDS_LIB standard
J 0
(2425 1450);
DISPLAY INVISIBLE (2425 1450);
FORCEADD OFFPAGE..3
R 6
(4325 2150);
FORCEPROP 2 LAST $XR0 12 
J 0
(4539 2150);
DISPLAY 0.638298 (4539 2150);
PAINT MONO (4539 2150);
FORCEPROP 1 LAST OFFPAGE TRUE
R 2
J 2
(4650 2275);
DISPLAY 0.872340 (4650 2275);
PAINT GREEN (4650 2275);
DISPLAY INVISIBLE (4650 2275);
FORCEPROP 1 LAST COMMENT_BODY TRUE
R 2
J 2
(4275 2250);
DISPLAY 0.872340 (4275 2250);
PAINT PEACH (4275 2250);
DISPLAY INVISIBLE (4275 2250);
FORCEPROP 2 LAST PATH I121
J 0
(4525 2225);
DISPLAY 0.680851 (4525 2225);
DISPLAY INVISIBLE (4525 2225);
FORCEPROP 2 LAST CDS_LIB standard
J 0
(4325 2150);
DISPLAY INVISIBLE (4325 2150);
FORCEADD OFFPAGE..1
(2425 1500);
FORCEPROP 2 LAST $XR0 21 
J 0
(2204 1500);
DISPLAY 0.638298 (2204 1500);
PAINT MONO (2204 1500);
FORCEPROP 1 LAST COMMENT_BODY TRUE
J 0
(2550 1400);
DISPLAY 0.872340 (2550 1400);
PAINT PEACH (2550 1400);
DISPLAY INVISIBLE (2550 1400);
FORCEPROP 1 LAST OFFPAGE TRUE
J 0
(2750 1375);
DISPLAY 0.872340 (2750 1375);
PAINT GREEN (2750 1375);
DISPLAY INVISIBLE (2750 1375);
FORCEPROP 2 LAST PATH I122
J 0
(2475 1575);
DISPLAY 0.680851 (2475 1575);
DISPLAY INVISIBLE (2475 1575);
FORCEPROP 2 LAST CDS_LIB standard
J 0
(2425 1500);
DISPLAY INVISIBLE (2425 1500);
FORCEADD OFFPAGE..3
R 6
(4325 2250);
FORCEPROP 2 LAST $XR0 12 
J 0
(4539 2250);
DISPLAY 0.638298 (4539 2250);
PAINT MONO (4539 2250);
FORCEPROP 1 LAST OFFPAGE TRUE
R 2
J 2
(4650 2375);
DISPLAY 0.872340 (4650 2375);
PAINT GREEN (4650 2375);
DISPLAY INVISIBLE (4650 2375);
FORCEPROP 1 LAST COMMENT_BODY TRUE
R 2
J 2
(4275 2350);
DISPLAY 0.872340 (4275 2350);
PAINT PEACH (4275 2350);
DISPLAY INVISIBLE (4275 2350);
FORCEPROP 2 LAST PATH I123
J 0
(4525 2325);
DISPLAY 0.680851 (4525 2325);
DISPLAY INVISIBLE (4525 2325);
FORCEPROP 2 LAST CDS_LIB standard
J 0
(4325 2250);
DISPLAY INVISIBLE (4325 2250);
FORCEADD UNIVERSAL_GND..1
(4950 3375);
FORCEPROP 3 LASTPIN (4950 3425) SIG_NAME GND\g
J 0
(4960 3435);
DISPLAY 0.659574 (4960 3435);
PAINT MONO (4960 3435);
DISPLAY INVISIBLE (4960 3435);
FORCEPROP 2 LAST CDS_LIB logical_power
J 0
(4950 3375);
DISPLAY INVISIBLE (4950 3375);
FORCEPROP 1 LAST HDL_POWER GND
J 1
(4975 3300);
DISPLAY 0.702128 (4975 3300);
PAINT GREEN (4975 3300);
DISPLAY INVISIBLE (4975 3300);
FORCEPROP 1 LAST PATH I124
J 0
(5025 3375);
DISPLAY 0.872340 (5025 3375);
PAINT AQUA (5025 3375);
DISPLAY INVISIBLE (5025 3375);
FORCEADD Q_RES..2
(4950 3650);
FORCEPROP 1 LAST VALUE 1K
J 0
(4995 3725);
DISPLAY 0.510638 (4995 3725);
PAINT SKYBLUE (4995 3725);
FORCEPROP 1 LAST MATERIAL EMPTY
J 0
(4975 3525);
DISPLAY 0.510638 (4975 3525);
PAINT RED (4975 3525);
FORCEPROP 1 LAST PART_NUMBER TMP_QCS21002FB24
R 3
J 0
(4875 3800);
DISPLAY 0.510638 (4875 3800);
PAINT WHITE (4875 3800);
FORCEPROP 1 LAST PATH I125
J 0
(5000 3825);
DISPLAY 0.978723 (5000 3825);
PAINT WHITE (5000 3825);
DISPLAY INVISIBLE (5000 3825);
FORCEPROP 2 LAST SEC_TYPE 0402LF
J 0
(5000 3875);
DISPLAY 0.680851 (5000 3875);
DISPLAY INVISIBLE (5000 3875);
FORCEPROP 2 LAST CDS_LIB pure_quanta
J 0
(4950 3650);
DISPLAY INVISIBLE (4950 3650);
FORCEPROP 1 LAST WATTAGE 1/16W
J 0
(4990 3625);
DISPLAY 0.510638 (4990 3625);
PAINT SKYBLUE (4990 3625);
DISPLAY INVISIBLE (4990 3625);
FORCEPROP 1 LAST TOLERANCE 1%
J 0
(4995 3675);
DISPLAY 0.510638 (4995 3675);
PAINT SKYBLUE (4995 3675);
DISPLAY INVISIBLE (4995 3675);
FORCEPROP 1 LAST PACK_TYPE 0402LF
J 0
(5000 3575);
DISPLAY 0.510638 (5000 3575);
PAINT SKYBLUE (5000 3575);
DISPLAY INVISIBLE (5000 3575);
FORCEPROP 1 LAST LOCATION R665
J 0
(4995 3775);
DISPLAY 0.702128 (4995 3775);
PAINT YELLOW (4995 3775);
FORCEPROP 1 LASTPIN (4950 3750) $PN 1
J 0
(4955 3712);
DISPLAY 0.808511 (4955 3712);
PAINT WHITE (4955 3712);
FORCEPROP 1 LASTPIN (4950 3550) $PN 2
J 0
(4955 3560);
DISPLAY 0.808511 (4955 3560);
PAINT WHITE (4955 3560);
FORCEPROP 2 LAST SEC 1
J 0
(5000 3875);
DISPLAY 0.680851 (5000 3875);
PAINT MONO (5000 3875);
DISPLAY INVISIBLE (5000 3875);
FORCEADD OFFPAGE..1
R 2
(5550 3925);
FORCEPROP 2 LAST $XR0 25 
J 0
(5736 3925);
DISPLAY 0.638298 (5736 3925);
PAINT MONO (5736 3925);
FORCEPROP 2 LAST PATH I126
J 2
(5500 4000);
DISPLAY 0.680851 (5500 4000);
DISPLAY INVISIBLE (5500 4000);
FORCEPROP 2 LAST CDS_LIB standard
J 2
(5550 3925);
DISPLAY INVISIBLE (5550 3925);
FORCEPROP 1 LAST OFFPAGE TRUE
J 2
(5225 3800);
DISPLAY 0.872340 (5225 3800);
PAINT GREEN (5225 3800);
DISPLAY INVISIBLE (5225 3800);
FORCEPROP 1 LAST COMMENT_BODY TRUE
J 2
(5425 3825);
DISPLAY 0.872340 (5425 3825);
PAINT PEACH (5425 3825);
DISPLAY INVISIBLE (5425 3825);
FORCEADD OFFPAGE..1
R 2
(5550 3975);
FORCEPROP 2 LAST $XR0 25 
J 0
(5736 3975);
DISPLAY 0.638298 (5736 3975);
PAINT MONO (5736 3975);
FORCEPROP 2 LAST PATH I127
J 0
(5725 4050);
DISPLAY 0.680851 (5725 4050);
DISPLAY INVISIBLE (5725 4050);
FORCEPROP 2 LAST CDS_LIB standard
J 2
(5550 3975);
DISPLAY INVISIBLE (5550 3975);
FORCEPROP 1 LAST OFFPAGE TRUE
J 2
(5225 3850);
DISPLAY 0.872340 (5225 3850);
PAINT GREEN (5225 3850);
DISPLAY INVISIBLE (5225 3850);
FORCEPROP 1 LAST COMMENT_BODY TRUE
J 2
(5425 3875);
DISPLAY 0.872340 (5425 3875);
PAINT PEACH (5425 3875);
DISPLAY INVISIBLE (5425 3875);
FORCEADD Q_RES..2
(4675 3650);
FORCEPROP 1 LAST MATERIAL EMPTY
J 0
(4700 3525);
DISPLAY 0.510638 (4700 3525);
PAINT RED (4700 3525);
FORCEPROP 1 LAST PART_NUMBER TMP_QCS21002FB24
R 3
J 0
(4600 3800);
DISPLAY 0.510638 (4600 3800);
PAINT WHITE (4600 3800);
FORCEPROP 1 LAST VALUE 1K
J 0
(4720 3725);
DISPLAY 0.510638 (4720 3725);
PAINT SKYBLUE (4720 3725);
FORCEPROP 2 LAST CDS_LIB pure_quanta
J 0
(4675 3650);
DISPLAY INVISIBLE (4675 3650);
FORCEPROP 2 LAST SEC_TYPE 0402LF
J 0
(4725 3875);
DISPLAY 0.680851 (4725 3875);
DISPLAY INVISIBLE (4725 3875);
FORCEPROP 1 LAST PATH I128
J 0
(4725 3825);
DISPLAY 0.978723 (4725 3825);
PAINT WHITE (4725 3825);
DISPLAY INVISIBLE (4725 3825);
FORCEPROP 1 LAST TOLERANCE 1%
J 0
(4720 3675);
DISPLAY 0.510638 (4720 3675);
PAINT SKYBLUE (4720 3675);
DISPLAY INVISIBLE (4720 3675);
FORCEPROP 1 LAST PACK_TYPE 0402LF
J 0
(4725 3575);
DISPLAY 0.510638 (4725 3575);
PAINT SKYBLUE (4725 3575);
DISPLAY INVISIBLE (4725 3575);
FORCEPROP 1 LAST WATTAGE 1/16W
J 0
(4715 3625);
DISPLAY 0.510638 (4715 3625);
PAINT SKYBLUE (4715 3625);
DISPLAY INVISIBLE (4715 3625);
FORCEPROP 1 LAST LOCATION R664
J 0
(4720 3775);
DISPLAY 0.702128 (4720 3775);
PAINT YELLOW (4720 3775);
FORCEPROP 1 LASTPIN (4675 3750) $PN 1
J 0
(4680 3712);
DISPLAY 0.808511 (4680 3712);
PAINT WHITE (4680 3712);
FORCEPROP 1 LASTPIN (4675 3550) $PN 2
J 0
(4680 3560);
DISPLAY 0.808511 (4680 3560);
PAINT WHITE (4680 3560);
FORCEPROP 2 LAST SEC 1
J 0
(4725 3875);
DISPLAY 0.680851 (4725 3875);
PAINT MONO (4725 3875);
DISPLAY INVISIBLE (4725 3875);
FORCEADD OFFPAGE..1
R 4
(4700 2850);
FORCEPROP 2 LAST $XR0 13 
J 0
(4886 2850);
DISPLAY 0.638298 (4886 2850);
PAINT MONO (4886 2850);
FORCEPROP 2 LAST $XR1 27 
J 0
(4976 2850);
DISPLAY 0.638298 (4976 2850);
PAINT MONO (4976 2850);
FORCEPROP 1 LAST COMMENT_BODY TRUE
R 2
J 0
(4575 2950);
DISPLAY 0.872340 (4575 2950);
PAINT PEACH (4575 2950);
DISPLAY INVISIBLE (4575 2950);
FORCEPROP 1 LAST OFFPAGE TRUE
R 2
J 0
(4375 2975);
DISPLAY 0.872340 (4375 2975);
PAINT GREEN (4375 2975);
DISPLAY INVISIBLE (4375 2975);
FORCEPROP 2 LAST CDS_LIB standard
R 2
J 0
(4700 2850);
DISPLAY INVISIBLE (4700 2850);
FORCEPROP 2 LAST PATH I133
R 2
J 0
(4950 2800);
DISPLAY 0.680851 (4950 2800);
DISPLAY INVISIBLE (4950 2800);
FORCEADD OFFPAGE..1
R 4
(4700 2700);
FORCEPROP 2 LAST $XR0 13 
J 0
(4886 2700);
DISPLAY 0.638298 (4886 2700);
PAINT MONO (4886 2700);
FORCEPROP 1 LAST COMMENT_BODY TRUE
R 2
J 0
(4575 2800);
DISPLAY 0.872340 (4575 2800);
PAINT PEACH (4575 2800);
DISPLAY INVISIBLE (4575 2800);
FORCEPROP 1 LAST OFFPAGE TRUE
R 2
J 0
(4375 2825);
DISPLAY 0.872340 (4375 2825);
PAINT GREEN (4375 2825);
DISPLAY INVISIBLE (4375 2825);
FORCEPROP 2 LAST CDS_LIB standard
R 2
J 0
(4700 2700);
DISPLAY INVISIBLE (4700 2700);
FORCEPROP 2 LAST PATH I134
R 2
J 0
(4900 2650);
DISPLAY 0.680851 (4900 2650);
DISPLAY INVISIBLE (4900 2650);
FORCEADD OFFPAGE..3
R 6
(4700 3000);
FORCEPROP 2 LAST $XR0 27 
J 0
(4914 3000);
DISPLAY 0.638298 (4914 3000);
PAINT MONO (4914 3000);
FORCEPROP 2 LAST $XR1 13 
J 0
(5004 3000);
DISPLAY 0.638298 (5004 3000);
PAINT MONO (5004 3000);
FORCEPROP 2 LAST CDS_LIB standard
R 2
J 0
(4700 3000);
DISPLAY INVISIBLE (4700 3000);
FORCEPROP 1 LAST OFFPAGE TRUE
R 2
J 2
(5025 3125);
DISPLAY 0.872340 (5025 3125);
PAINT GREEN (5025 3125);
DISPLAY INVISIBLE (5025 3125);
FORCEPROP 1 LAST COMMENT_BODY TRUE
R 2
J 2
(4650 3100);
DISPLAY 0.872340 (4650 3100);
PAINT PEACH (4650 3100);
DISPLAY INVISIBLE (4650 3100);
FORCEPROP 2 LAST PATH I135
R 2
J 0
(4975 2950);
DISPLAY 0.680851 (4975 2950);
DISPLAY INVISIBLE (4975 2950);
FORCEADD OFFPAGE..3
R 6
(4700 2950);
FORCEPROP 2 LAST $XR1 27 
J 0
(5004 2950);
DISPLAY 0.638298 (5004 2950);
PAINT MONO (5004 2950);
FORCEPROP 2 LAST $XR0 13 
J 0
(4914 2950);
DISPLAY 0.638298 (4914 2950);
PAINT MONO (4914 2950);
FORCEPROP 2 LAST CDS_LIB standard
R 2
J 0
(4700 2950);
DISPLAY INVISIBLE (4700 2950);
FORCEPROP 1 LAST OFFPAGE TRUE
R 2
J 2
(5025 3075);
DISPLAY 0.872340 (5025 3075);
PAINT GREEN (5025 3075);
DISPLAY INVISIBLE (5025 3075);
FORCEPROP 1 LAST COMMENT_BODY TRUE
R 2
J 2
(4650 3050);
DISPLAY 0.872340 (4650 3050);
PAINT PEACH (4650 3050);
DISPLAY INVISIBLE (4650 3050);
FORCEPROP 2 LAST PATH I136
R 2
J 0
(4975 2900);
DISPLAY 0.680851 (4975 2900);
DISPLAY INVISIBLE (4975 2900);
FORCEADD OFFPAGE..1
R 4
(4700 2750);
FORCEPROP 2 LAST $XR0 13 
J 0
(4886 2750);
DISPLAY 0.638298 (4886 2750);
PAINT MONO (4886 2750);
FORCEPROP 2 LAST PATH I138
J 0
(4875 2825);
DISPLAY 0.680851 (4875 2825);
DISPLAY INVISIBLE (4875 2825);
FORCEPROP 1 LAST COMMENT_BODY TRUE
R 2
J 0
(4575 2850);
DISPLAY 0.872340 (4575 2850);
PAINT PEACH (4575 2850);
DISPLAY INVISIBLE (4575 2850);
FORCEPROP 1 LAST OFFPAGE TRUE
R 2
J 0
(4375 2875);
DISPLAY 0.872340 (4375 2875);
PAINT GREEN (4375 2875);
DISPLAY INVISIBLE (4375 2875);
FORCEPROP 2 LAST CDS_LIB standard
R 2
J 0
(4700 2750);
DISPLAY INVISIBLE (4700 2750);
FORCEADD UNIVERSAL_POWER..1
(3100 4325);
FORCEPROP 3 LASTPIN (3100 4275) SIG_NAME P3V3_AUX\g
J 0
(3110 4285);
DISPLAY 0.659574 (3110 4285);
PAINT MONO (3110 4285);
DISPLAY INVISIBLE (3110 4285);
FORCEPROP 1 LAST HDL_POWER P3V3_AUX
J 1
(3100 4375);
DISPLAY 0.702128 (3100 4375);
PAINT GREEN (3100 4375);
FORCEPROP 2 LAST CDS_LIB logical_power
J 0
(3100 4325);
DISPLAY INVISIBLE (3100 4325);
FORCEPROP 1 LAST PATH I139
J 0
(3150 4350);
DISPLAY 0.872340 (3150 4350);
PAINT AQUA (3150 4350);
DISPLAY INVISIBLE (3150 4350);
FORCEADD OFFPAGE..2
(-1650 1950);
FORCEPROP 2 LAST $XR1 21 
J 0
(-3061 1950);
DISPLAY 0.638298 (-3061 1950);
PAINT MONO (-3061 1950);
FORCEPROP 2 LAST $XR0 13 
J 0
(-2971 1950);
DISPLAY 0.638298 (-2971 1950);
PAINT MONO (-2971 1950);
FORCEPROP 1 LAST COMMENT_BODY TRUE
J 0
(-1695 1855);
DISPLAY 0.872340 (-1695 1855);
PAINT GREEN (-1695 1855);
DISPLAY INVISIBLE (-1695 1855);
FORCEPROP 1 LAST OFFPAGE TRUE
J 0
(-1325 1825);
DISPLAY 0.872340 (-1325 1825);
DISPLAY INVISIBLE (-1325 1825);
FORCEPROP 2 LAST CDS_LIB standard
J 0
(-1650 1950);
DISPLAY INVISIBLE (-1650 1950);
FORCEPROP 2 LAST PATH I14
J 0
(-1450 2000);
DISPLAY 0.680851 (-1450 2000);
DISPLAY INVISIBLE (-1450 2000);
FORCEADD UNIVERSAL_GND..1
(1900 875);
FORCEPROP 3 LASTPIN (1900 925) SIG_NAME GND\g
J 0
(1910 935);
DISPLAY 0.659574 (1910 935);
PAINT MONO (1910 935);
DISPLAY INVISIBLE (1910 935);
FORCEPROP 2 LAST CDS_LIB logical_power
J 0
(1900 875);
DISPLAY INVISIBLE (1900 875);
FORCEPROP 1 LAST PATH I145
J 0
(1975 875);
DISPLAY 0.872340 (1975 875);
PAINT AQUA (1975 875);
DISPLAY INVISIBLE (1975 875);
FORCEPROP 1 LAST HDL_POWER GND
J 1
(1925 800);
DISPLAY 0.702128 (1925 800);
PAINT GREEN (1925 800);
DISPLAY INVISIBLE (1925 800);
FORCEADD UNIVERSAL_GND..1
(1125 900);
FORCEPROP 3 LASTPIN (1125 950) SIG_NAME GND\g
J 0
(1135 960);
DISPLAY 0.659574 (1135 960);
PAINT MONO (1135 960);
DISPLAY INVISIBLE (1135 960);
FORCEPROP 1 LAST HDL_POWER GND
J 1
(1150 825);
DISPLAY 0.702128 (1150 825);
PAINT GREEN (1150 825);
DISPLAY INVISIBLE (1150 825);
FORCEPROP 1 LAST PATH I146
J 0
(1200 900);
DISPLAY 0.872340 (1200 900);
PAINT AQUA (1200 900);
DISPLAY INVISIBLE (1200 900);
FORCEPROP 2 LAST CDS_LIB logical_power
J 0
(1125 900);
DISPLAY INVISIBLE (1125 900);
FORCEADD Q_RES..2
(225 3725);
FORCEPROP 1 LAST VALUE 4.7K
J 0
(275 3750);
DISPLAY 0.510638 (275 3750);
PAINT SKYBLUE (275 3750);
FORCEPROP 1 LAST MATERIAL EMPTY
J 0
(250 3625);
DISPLAY 0.510638 (250 3625);
PAINT RED (250 3625);
FORCEPROP 1 LAST TOLERANCE 1%
J 0
(275 3700);
DISPLAY 0.510638 (275 3700);
PAINT SKYBLUE (275 3700);
FORCEPROP 1 LAST PART_NUMBER CS24702FB10
J 0
(265 3600);
DISPLAY 0.510638 (265 3600);
PAINT WHITE (265 3600);
DISPLAY INVISIBLE (265 3600);
FORCEPROP 1 LAST WATTAGE 1/16W
J 0
(265 3700);
DISPLAY 0.510638 (265 3700);
PAINT SKYBLUE (265 3700);
DISPLAY INVISIBLE (265 3700);
FORCEPROP 1 LAST PACK_TYPE 0402LF
J 0
(265 3550);
DISPLAY 0.510638 (265 3550);
PAINT SKYBLUE (265 3550);
DISPLAY INVISIBLE (265 3550);
FORCEPROP 1 LAST PATH I147
J 0
(275 3900);
DISPLAY 0.978723 (275 3900);
PAINT WHITE (275 3900);
DISPLAY INVISIBLE (275 3900);
FORCEPROP 2 LAST CDS_LIB pure_quanta
J 0
(225 3725);
DISPLAY INVISIBLE (225 3725);
FORCEPROP 1 LAST $LOCATION R543
J 0
(275 3800);
DISPLAY 0.702128 (275 3800);
PAINT YELLOW (275 3800);
FORCEPROP 1 LASTPIN (225 3825) $PN 1
J 0
(230 3787);
DISPLAY 0.787234 (230 3787);
PAINT MONO (230 3787);
FORCEPROP 1 LASTPIN (225 3625) $PN 2
J 0
(230 3635);
DISPLAY 0.787234 (230 3635);
PAINT MONO (230 3635);
FORCEPROP 0 LAST CDS_LOCATION R543
J 0
(275 3850);
DISPLAY 0.680851 (275 3850);
DISPLAY INVISIBLE (275 3850);
FORCEPROP 0 LAST $SEC 1
J 0
(275 3850);
DISPLAY 0.680851 (275 3850);
PAINT MONO (275 3850);
DISPLAY INVISIBLE (275 3850);
FORCEPROP 0 LAST CDS_SEC 1
J 0
(275 3850);
DISPLAY 0.680851 (275 3850);
DISPLAY INVISIBLE (275 3850);
FORCEADD UNIVERSAL_POWER..1
(200 3975);
FORCEPROP 3 LASTPIN (200 3925) SIG_NAME P3V3_AUX\g
J 0
(210 3935);
DISPLAY 0.659574 (210 3935);
PAINT MONO (210 3935);
DISPLAY INVISIBLE (210 3935);
FORCEPROP 1 LAST HDL_POWER P3V3_AUX
J 1
(200 4025);
DISPLAY 0.702128 (200 4025);
PAINT GREEN (200 4025);
FORCEPROP 2 LAST CDS_LIB logical_power
J 0
(200 3975);
DISPLAY INVISIBLE (200 3975);
FORCEPROP 1 LAST PATH I148
J 0
(250 4000);
DISPLAY 0.872340 (250 4000);
PAINT AQUA (250 4000);
DISPLAY INVISIBLE (250 4000);
FORCEADD OFFPAGE..4
(4700 3100);
FORCEPROP 2 LAST $XR0 25 
J 0
(4886 3100);
DISPLAY 0.638298 (4886 3100);
PAINT MONO (4886 3100);
FORCEPROP 2 LAST $XR1 21 
J 0
(4976 3100);
DISPLAY 0.638298 (4976 3100);
PAINT MONO (4976 3100);
FORCEPROP 2 LAST PATH I149
J 0
(4900 3150);
DISPLAY 0.680851 (4900 3150);
DISPLAY INVISIBLE (4900 3150);
FORCEPROP 1 LAST COMMENT_BODY TRUE
J 0
(4675 3000);
DISPLAY 0.872340 (4675 3000);
PAINT PEACH (4675 3000);
DISPLAY INVISIBLE (4675 3000);
FORCEPROP 1 LAST OFFPAGE TRUE
J 0
(5025 2975);
DISPLAY 0.872340 (5025 2975);
PAINT GREEN (5025 2975);
DISPLAY INVISIBLE (5025 2975);
FORCEPROP 2 LAST CDS_LIB standard
J 0
(4700 3100);
DISPLAY INVISIBLE (4700 3100);
FORCEADD OFFPAGE..4
(4700 3150);
FORCEPROP 2 LAST $XR0 25 
J 0
(4886 3150);
DISPLAY 0.638298 (4886 3150);
PAINT MONO (4886 3150);
FORCEPROP 2 LAST $XR1 21 
J 0
(4976 3150);
DISPLAY 0.638298 (4976 3150);
PAINT MONO (4976 3150);
FORCEPROP 1 LAST COMMENT_BODY TRUE
J 0
(4675 3050);
DISPLAY 0.872340 (4675 3050);
PAINT PEACH (4675 3050);
DISPLAY INVISIBLE (4675 3050);
FORCEPROP 1 LAST OFFPAGE TRUE
J 0
(5025 3025);
DISPLAY 0.872340 (5025 3025);
PAINT GREEN (5025 3025);
DISPLAY INVISIBLE (5025 3025);
FORCEPROP 2 LAST CDS_LIB standard
J 0
(4700 3150);
DISPLAY INVISIBLE (4700 3150);
FORCEPROP 2 LAST PATH I152
J 0
(4900 3200);
DISPLAY 0.680851 (4900 3200);
DISPLAY INVISIBLE (4900 3200);
FORCEADD OFFPAGE..6
(-1000 2550);
FORCEPROP 2 LAST $XR2 36 
J 0
(-1459 2550);
DISPLAY 0.638298 (-1459 2550);
PAINT MONO (-1459 2550);
FORCEPROP 2 LAST $XR3 46 
J 0
(-1549 2550);
DISPLAY 0.638298 (-1549 2550);
PAINT MONO (-1549 2550);
FORCEPROP 2 LAST $XR1 34 
J 0
(-1369 2550);
DISPLAY 0.638298 (-1369 2550);
PAINT MONO (-1369 2550);
FORCEPROP 2 LAST $XR0 12 
J 0
(-1279 2550);
DISPLAY 0.638298 (-1279 2550);
PAINT MONO (-1279 2550);
FORCEPROP 2 LAST PATH I154
J 0
(-1225 2600);
DISPLAY 0.680851 (-1225 2600);
DISPLAY INVISIBLE (-1225 2600);
FORCEPROP 1 LAST COMMENT_BODY TRUE
J 0
(-900 2475);
DISPLAY 0.872340 (-900 2475);
PAINT PEACH (-900 2475);
DISPLAY INVISIBLE (-900 2475);
FORCEPROP 1 LAST OFFPAGE TRUE
J 0
(-675 2425);
DISPLAY 0.872340 (-675 2425);
PAINT GREEN (-675 2425);
DISPLAY INVISIBLE (-675 2425);
FORCEPROP 2 LAST CDS_LIB standard
J 0
(-1000 2550);
DISPLAY INVISIBLE (-1000 2550);
FORCEADD OFFPAGE..1
(-1000 2600);
FORCEPROP 2 LAST $XR3 46 
J 0
(-1551 2600);
DISPLAY 0.638298 (-1551 2600);
PAINT MONO (-1551 2600);
FORCEPROP 2 LAST $XR0 12 
J 0
(-1281 2600);
DISPLAY 0.638298 (-1281 2600);
PAINT MONO (-1281 2600);
FORCEPROP 2 LAST $XR1 34 
J 0
(-1371 2600);
DISPLAY 0.638298 (-1371 2600);
PAINT MONO (-1371 2600);
FORCEPROP 2 LAST $XR2 36 
J 0
(-1461 2600);
DISPLAY 0.638298 (-1461 2600);
PAINT MONO (-1461 2600);
FORCEPROP 2 LAST PATH I155
J 0
(-1250 2650);
DISPLAY 0.680851 (-1250 2650);
DISPLAY INVISIBLE (-1250 2650);
FORCEPROP 2 LAST CDS_LIB standard
J 0
(-1000 2600);
DISPLAY INVISIBLE (-1000 2600);
FORCEPROP 1 LAST OFFPAGE TRUE
J 0
(-675 2475);
DISPLAY 0.872340 (-675 2475);
PAINT GREEN (-675 2475);
DISPLAY INVISIBLE (-675 2475);
FORCEPROP 1 LAST COMMENT_BODY TRUE
J 0
(-875 2500);
DISPLAY 0.872340 (-875 2500);
PAINT PEACH (-875 2500);
DISPLAY INVISIBLE (-875 2500);
FORCEADD Q_RES..1
(100 2550);
FORCEPROP 1 LAST VALUE 33.2
J 0
(200 2550);
DISPLAY 0.510638 (200 2550);
PAINT SKYBLUE (200 2550);
FORCEPROP 1 LAST MATERIAL CHIP
J 2
(400 2550);
DISPLAY 0.510638 (400 2550);
PAINT SKYBLUE (400 2550);
FORCEPROP 1 LAST TOLERANCE 1%
J 0
(225 2550);
DISPLAY 0.510638 (225 2550);
PAINT SKYBLUE (225 2550);
DISPLAY INVISIBLE (225 2550);
FORCEPROP 1 LAST PART_NUMBER CS03322FB03
J 0
(50 2650);
DISPLAY 0.510638 (50 2650);
PAINT WHITE (50 2650);
DISPLAY INVISIBLE (50 2650);
FORCEPROP 1 LAST PACK_TYPE 0402LF
J 0
(350 2400);
DISPLAY 0.510638 (350 2400);
PAINT SKYBLUE (350 2400);
DISPLAY INVISIBLE (350 2400);
FORCEPROP 1 LAST WATTAGE 1/16W
J 2
(75 2400);
DISPLAY 0.510638 (75 2400);
PAINT SKYBLUE (75 2400);
DISPLAY INVISIBLE (75 2400);
FORCEPROP 2 LAST CDS_LIB pure_quanta
J 0
(100 2550);
DISPLAY INVISIBLE (100 2550);
FORCEPROP 2 LAST SEC_TYPE 0402LF
J 0
(50 2750);
DISPLAY 0.680851 (50 2750);
DISPLAY INVISIBLE (50 2750);
FORCEPROP 1 LAST PATH I156
J 0
(50 2700);
DISPLAY 0.978723 (50 2700);
PAINT WHITE (50 2700);
DISPLAY INVISIBLE (50 2700);
FORCEPROP 1 LAST $LOCATION R850
J 2
(-25 2550);
DISPLAY 0.702128 (-25 2550);
PAINT YELLOW (-25 2550);
FORCEPROP 1 LASTPIN (0 2550) $PN 1
J 0
(12 2562);
DISPLAY 0.808511 (12 2562);
PAINT WHITE (12 2562);
FORCEPROP 1 LASTPIN (200 2550) $PN 2
J 0
(162 2562);
DISPLAY 0.808511 (162 2562);
PAINT WHITE (162 2562);
FORCEPROP 0 LAST CDS_LOCATION R850
J 0
(-25 2600);
DISPLAY 0.680851 (-25 2600);
DISPLAY INVISIBLE (-25 2600);
FORCEPROP 0 LAST SEC 1
J 0
(-150 2600);
DISPLAY 0.680851 (-150 2600);
PAINT MONO (-150 2600);
DISPLAY INVISIBLE (-150 2600);
FORCEADD Q_RES..1
(100 2600);
FORCEPROP 1 LAST VALUE 33.2
J 0
(200 2600);
DISPLAY 0.510638 (200 2600);
PAINT SKYBLUE (200 2600);
FORCEPROP 1 LAST MATERIAL CHIP
J 2
(400 2600);
DISPLAY 0.510638 (400 2600);
PAINT SKYBLUE (400 2600);
FORCEPROP 2 LAST SEC_TYPE 0402LF
J 0
(50 2800);
DISPLAY 0.680851 (50 2800);
DISPLAY INVISIBLE (50 2800);
FORCEPROP 2 LAST CDS_LIB pure_quanta
J 0
(100 2600);
DISPLAY INVISIBLE (100 2600);
FORCEPROP 1 LAST WATTAGE 1/16W
J 2
(75 2450);
DISPLAY 0.510638 (75 2450);
PAINT SKYBLUE (75 2450);
DISPLAY INVISIBLE (75 2450);
FORCEPROP 1 LAST PACK_TYPE 0402LF
J 0
(350 2450);
DISPLAY 0.510638 (350 2450);
PAINT SKYBLUE (350 2450);
DISPLAY INVISIBLE (350 2450);
FORCEPROP 1 LAST PART_NUMBER CS03322FB03
J 0
(50 2700);
DISPLAY 0.510638 (50 2700);
PAINT WHITE (50 2700);
DISPLAY INVISIBLE (50 2700);
FORCEPROP 1 LAST TOLERANCE 1%
J 0
(225 2600);
DISPLAY 0.510638 (225 2600);
PAINT SKYBLUE (225 2600);
DISPLAY INVISIBLE (225 2600);
FORCEPROP 1 LAST PATH I157
J 0
(50 2750);
DISPLAY 0.978723 (50 2750);
PAINT WHITE (50 2750);
DISPLAY INVISIBLE (50 2750);
FORCEPROP 1 LAST $LOCATION R849
J 2
(-25 2600);
DISPLAY 0.702128 (-25 2600);
PAINT YELLOW (-25 2600);
FORCEPROP 1 LASTPIN (0 2600) $PN 1
J 0
(12 2612);
DISPLAY 0.808511 (12 2612);
PAINT WHITE (12 2612);
FORCEPROP 1 LASTPIN (200 2600) $PN 2
J 0
(162 2612);
DISPLAY 0.808511 (162 2612);
PAINT WHITE (162 2612);
FORCEPROP 0 LAST CDS_LOCATION R849
J 0
(-25 2650);
DISPLAY 0.680851 (-25 2650);
DISPLAY INVISIBLE (-25 2650);
FORCEPROP 0 LAST SEC 1
J 0
(-150 2650);
DISPLAY 0.680851 (-150 2650);
PAINT MONO (-150 2650);
DISPLAY INVISIBLE (-150 2650);
FORCEADD UNIVERSAL_POWER..1
(-1750 2500);
FORCEPROP 3 LASTPIN (-1750 2450) SIG_NAME P3V3_AUX\g
J 0
(-1740 2460);
DISPLAY 0.659574 (-1740 2460);
PAINT MONO (-1740 2460);
DISPLAY INVISIBLE (-1740 2460);
FORCEPROP 1 LAST HDL_POWER P3V3_AUX
J 1
(-1750 2550);
DISPLAY 0.702128 (-1750 2550);
PAINT GREEN (-1750 2550);
FORCEPROP 1 LAST PATH I160
J 0
(-1700 2525);
DISPLAY 0.872340 (-1700 2525);
PAINT AQUA (-1700 2525);
DISPLAY INVISIBLE (-1700 2525);
FORCEPROP 2 LAST CDS_LIB logical_power
J 0
(-1750 2500);
DISPLAY INVISIBLE (-1750 2500);
FORCEADD Q_RES..1
(100 2450);
FORCEPROP 1 LAST VALUE 1K
J 2
(425 2450);
DISPLAY 0.510638 (425 2450);
PAINT SKYBLUE (425 2450);
FORCEPROP 1 LAST MATERIAL EMPTY
J 0
(250 2450);
DISPLAY 0.510638 (250 2450);
PAINT RED (250 2450);
FORCEPROP 1 LAST PACK_TYPE 0402LF
J 0
(150 2400);
DISPLAY 0.510638 (150 2400);
PAINT SKYBLUE (150 2400);
DISPLAY INVISIBLE (150 2400);
FORCEPROP 1 LAST WATTAGE 1/16W
J 2
(25 2400);
DISPLAY 0.510638 (25 2400);
PAINT SKYBLUE (25 2400);
DISPLAY INVISIBLE (25 2400);
FORCEPROP 1 LAST TOLERANCE 1%
J 0
(50 2400);
DISPLAY 0.510638 (50 2400);
PAINT SKYBLUE (50 2400);
DISPLAY INVISIBLE (50 2400);
FORCEPROP 1 LAST PART_NUMBER CS21002FB06
J 0
(50 2550);
DISPLAY 0.510638 (50 2550);
PAINT WHITE (50 2550);
DISPLAY INVISIBLE (50 2550);
FORCEPROP 1 LAST PATH I161
J 0
(50 2600);
DISPLAY 0.978723 (50 2600);
PAINT WHITE (50 2600);
DISPLAY INVISIBLE (50 2600);
FORCEPROP 2 LAST CDS_LIB pure_quanta
J 0
(100 2450);
DISPLAY INVISIBLE (100 2450);
FORCEPROP 1 LAST $LOCATION R867
J 0
(-125 2450);
DISPLAY 0.702128 (-125 2450);
PAINT YELLOW (-125 2450);
FORCEPROP 1 LASTPIN (0 2450) $PN 1
J 0
(12 2462);
DISPLAY 0.787234 (12 2462);
PAINT MONO (12 2462);
FORCEPROP 1 LASTPIN (200 2450) $PN 2
J 0
(162 2462);
DISPLAY 0.787234 (162 2462);
PAINT MONO (162 2462);
FORCEPROP 0 LAST CDS_LOCATION R867
J 0
(-200 2500);
DISPLAY 0.680851 (-200 2500);
DISPLAY INVISIBLE (-200 2500);
FORCEPROP 0 LAST $SEC 1
J 0
(-200 2500);
DISPLAY 0.680851 (-200 2500);
PAINT MONO (-200 2500);
DISPLAY INVISIBLE (-200 2500);
FORCEPROP 0 LAST CDS_SEC 1
J 0
(-200 2500);
DISPLAY 0.680851 (-200 2500);
DISPLAY INVISIBLE (-200 2500);
FORCEADD OFFPAGE..5
(-975 3200);
FORCEPROP 2 LAST $XR0 15 
J 0
(-1199 3200);
DISPLAY 0.638298 (-1199 3200);
PAINT MONO (-1199 3200);
FORCEPROP 2 LAST $XR1 34 
J 0
(-1289 3200);
DISPLAY 0.638298 (-1289 3200);
PAINT MONO (-1289 3200);
FORCEPROP 2 LAST PATH I162
J 0
(-1175 3250);
DISPLAY 0.680851 (-1175 3250);
DISPLAY INVISIBLE (-1175 3250);
FORCEPROP 1 LAST COMMENT_BODY TRUE
J 0
(-875 3125);
DISPLAY 0.872340 (-875 3125);
PAINT PEACH (-875 3125);
DISPLAY INVISIBLE (-875 3125);
FORCEPROP 1 LAST OFFPAGE TRUE
J 0
(-650 3075);
DISPLAY 0.872340 (-650 3075);
PAINT GREEN (-650 3075);
DISPLAY INVISIBLE (-650 3075);
FORCEPROP 2 LAST CDS_LIB standard
J 0
(-975 3200);
DISPLAY 0.808511 (-975 3200);
PAINT MONO (-975 3200);
DISPLAY INVISIBLE (-975 3200);
FORCEADD Q_RES..2
(500 3725);
FORCEPROP 1 LAST PACK_TYPE 0402LF
J 0
(540 3550);
DISPLAY 0.510638 (540 3550);
PAINT SKYBLUE (540 3550);
FORCEPROP 1 LAST MATERIAL CHIP
J 0
(540 3650);
DISPLAY 0.510638 (540 3650);
PAINT SKYBLUE (540 3650);
FORCEPROP 1 LAST PART_NUMBER CS31002FB08
J 0
(540 3600);
DISPLAY 0.510638 (540 3600);
PAINT WHITE (540 3600);
FORCEPROP 1 LAST VALUE 10K
J 0
(550 3700);
DISPLAY 0.510638 (550 3700);
PAINT SKYBLUE (550 3700);
FORCEPROP 1 LAST PATH I166
J 0
(550 3900);
DISPLAY 0.978723 (550 3900);
PAINT WHITE (550 3900);
DISPLAY INVISIBLE (550 3900);
FORCEPROP 2 LAST CDS_LIB pure_quanta
J 0
(500 3725);
DISPLAY INVISIBLE (500 3725);
FORCEPROP 1 LAST TOLERANCE 1%
J 0
(545 3750);
DISPLAY 0.510638 (545 3750);
PAINT SKYBLUE (545 3750);
DISPLAY INVISIBLE (545 3750);
FORCEPROP 1 LAST WATTAGE 1/16W
J 0
(540 3700);
DISPLAY 0.510638 (540 3700);
PAINT SKYBLUE (540 3700);
DISPLAY INVISIBLE (540 3700);
FORCEPROP 1 LAST $LOCATION R404
J 0
(550 3750);
DISPLAY 0.702128 (550 3750);
PAINT YELLOW (550 3750);
FORCEPROP 1 LASTPIN (500 3825) $PN 1
J 0
(505 3787);
DISPLAY 0.787234 (505 3787);
PAINT MONO (505 3787);
FORCEPROP 1 LASTPIN (500 3625) $PN 2
J 0
(505 3635);
DISPLAY 0.787234 (505 3635);
PAINT MONO (505 3635);
FORCEPROP 0 LAST CDS_LOCATION R404
J 0
(550 3800);
DISPLAY 0.680851 (550 3800);
DISPLAY INVISIBLE (550 3800);
FORCEPROP 0 LAST $SEC 1
J 0
(550 3800);
DISPLAY 0.680851 (550 3800);
PAINT MONO (550 3800);
DISPLAY INVISIBLE (550 3800);
FORCEPROP 0 LAST CDS_SEC 1
J 0
(550 3800);
DISPLAY 0.680851 (550 3800);
DISPLAY INVISIBLE (550 3800);
FORCEADD Q_RES..1
(-150 3200);
FORCEPROP 1 LAST VALUE 0
J 2
(25 3200);
DISPLAY 0.787234 (25 3200);
PAINT SKYBLUE (25 3200);
FORCEPROP 1 LAST MATERIAL CHIP
J 0
(75 3200);
DISPLAY 0.787234 (75 3200);
PAINT SKYBLUE (75 3200);
FORCEPROP 2 LAST CDS_LIB pure_quanta
J 0
(-150 3200);
DISPLAY INVISIBLE (-150 3200);
FORCEPROP 1 LAST PATH I167
J 0
(-200 3350);
DISPLAY 0.978723 (-200 3350);
PAINT WHITE (-200 3350);
DISPLAY INVISIBLE (-200 3350);
FORCEPROP 1 LAST TOLERANCE 5%
J 0
(-150 3100);
DISPLAY 0.978723 (-150 3100);
DISPLAY INVISIBLE (-150 3100);
FORCEPROP 1 LAST WATTAGE 1/16W
J 2
(-175 3050);
DISPLAY 0.978723 (-175 3050);
DISPLAY INVISIBLE (-175 3050);
FORCEPROP 1 LAST PACK_TYPE 0402LF
J 0
(100 3050);
DISPLAY 0.978723 (100 3050);
DISPLAY INVISIBLE (100 3050);
FORCEPROP 1 LAST PART_NUMBER CS00002JB13
J 0
(-200 3300);
DISPLAY 0.978723 (-200 3300);
DISPLAY INVISIBLE (-200 3300);
FORCEPROP 1 LAST $LOCATION R57
J 0
(-375 3200);
DISPLAY 0.787234 (-375 3200);
PAINT YELLOW (-375 3200);
FORCEPROP 1 LASTPIN (-250 3200) $PN 1
J 0
(-238 3212);
DISPLAY 0.787234 (-238 3212);
PAINT MONO (-238 3212);
FORCEPROP 1 LASTPIN (-50 3200) $PN 2
J 0
(-88 3212);
DISPLAY 0.787234 (-88 3212);
PAINT MONO (-88 3212);
FORCEPROP 0 LAST CDS_LOCATION R57
J 0
(75 3250);
DISPLAY 0.680851 (75 3250);
DISPLAY INVISIBLE (75 3250);
FORCEPROP 0 LAST $SEC 1
J 0
(75 3250);
DISPLAY 0.680851 (75 3250);
PAINT MONO (75 3250);
DISPLAY INVISIBLE (75 3250);
FORCEPROP 0 LAST CDS_SEC 1
J 0
(75 3250);
DISPLAY 0.680851 (75 3250);
DISPLAY INVISIBLE (75 3250);
FORCEADD Q_RES..2
(50 3725);
FORCEPROP 1 LAST VALUE 4.7K
J 0
(100 3750);
DISPLAY 0.510638 (100 3750);
PAINT SKYBLUE (100 3750);
FORCEPROP 1 LAST MATERIAL EMPTY
J 0
(75 3625);
DISPLAY 0.510638 (75 3625);
PAINT RED (75 3625);
FORCEPROP 1 LAST TOLERANCE 1%
J 0
(100 3700);
DISPLAY 0.510638 (100 3700);
PAINT SKYBLUE (100 3700);
FORCEPROP 2 LAST CDS_LIB pure_quanta
J 0
(50 3725);
DISPLAY INVISIBLE (50 3725);
FORCEPROP 1 LAST PATH I168
J 0
(100 3900);
DISPLAY 0.978723 (100 3900);
PAINT WHITE (100 3900);
DISPLAY INVISIBLE (100 3900);
FORCEPROP 1 LAST PART_NUMBER CS24702FB10
J 0
(90 3600);
DISPLAY 0.510638 (90 3600);
PAINT WHITE (90 3600);
DISPLAY INVISIBLE (90 3600);
FORCEPROP 1 LAST WATTAGE 1/16W
J 0
(90 3700);
DISPLAY 0.510638 (90 3700);
PAINT SKYBLUE (90 3700);
DISPLAY INVISIBLE (90 3700);
FORCEPROP 1 LAST PACK_TYPE 0402LF
J 0
(90 3550);
DISPLAY 0.510638 (90 3550);
PAINT SKYBLUE (90 3550);
DISPLAY INVISIBLE (90 3550);
FORCEPROP 1 LAST $LOCATION R58
J 0
(75 3800);
DISPLAY 0.787234 (75 3800);
PAINT YELLOW (75 3800);
FORCEPROP 1 LASTPIN (50 3825) $PN 1
J 0
(55 3787);
DISPLAY 0.787234 (55 3787);
PAINT MONO (55 3787);
FORCEPROP 1 LASTPIN (50 3625) $PN 2
J 0
(55 3635);
DISPLAY 0.787234 (55 3635);
PAINT MONO (55 3635);
FORCEPROP 0 LAST CDS_LOCATION R58
J 0
(100 3900);
DISPLAY 0.680851 (100 3900);
DISPLAY INVISIBLE (100 3900);
FORCEPROP 0 LAST $SEC 1
J 0
(100 3900);
DISPLAY 0.680851 (100 3900);
PAINT MONO (100 3900);
DISPLAY INVISIBLE (100 3900);
FORCEPROP 0 LAST CDS_SEC 1
J 0
(100 3900);
DISPLAY 0.680851 (100 3900);
DISPLAY INVISIBLE (100 3900);
FORCEADD UNIVERSAL_POWER..1
(-2950 4450);
FORCEPROP 3 LASTPIN (-2950 4400) SIG_NAME P3V3_AUX\g
J 0
(-2940 4410);
DISPLAY 0.659574 (-2940 4410);
PAINT MONO (-2940 4410);
DISPLAY INVISIBLE (-2940 4410);
FORCEPROP 1 LAST HDL_POWER P3V3_AUX
J 1
(-2950 4500);
DISPLAY 0.702128 (-2950 4500);
PAINT GREEN (-2950 4500);
FORCEPROP 1 LAST PATH I169
J 0
(-2900 4475);
DISPLAY 0.872340 (-2900 4475);
PAINT AQUA (-2900 4475);
DISPLAY INVISIBLE (-2900 4475);
FORCEPROP 2 LAST CDS_LIB logical_power
J 0
(-2950 4450);
DISPLAY INVISIBLE (-2950 4450);
FORCEADD UNIVERSAL_POWER..1
(500 3975);
FORCEPROP 3 LASTPIN (500 3925) SIG_NAME P3V3_AUX\g
J 0
(510 3935);
DISPLAY 0.659574 (510 3935);
PAINT MONO (510 3935);
DISPLAY INVISIBLE (510 3935);
FORCEPROP 1 LAST HDL_POWER P3V3_AUX
J 1
(500 4025);
DISPLAY 0.702128 (500 4025);
PAINT GREEN (500 4025);
FORCEPROP 2 LAST CDS_LIB logical_power
J 0
(500 3975);
DISPLAY INVISIBLE (500 3975);
FORCEPROP 1 LAST PATH I171
J 0
(550 4000);
DISPLAY 0.872340 (550 4000);
PAINT AQUA (550 4000);
DISPLAY INVISIBLE (550 4000);
FORCEADD Q_RES..2
(-2575 2250);
FORCEPROP 1 LAST WATTAGE 1/16W
J 2
(-2600 2200);
DISPLAY 0.510638 (-2600 2200);
PAINT SKYBLUE (-2600 2200);
FORCEPROP 1 LAST PACK_TYPE 0402LF
J 2
(-2600 2100);
DISPLAY 0.510638 (-2600 2100);
PAINT SKYBLUE (-2600 2100);
FORCEPROP 1 LAST MATERIAL CHIP
J 2
(-2600 2150);
DISPLAY 0.510638 (-2600 2150);
PAINT SKYBLUE (-2600 2150);
FORCEPROP 1 LAST VALUE 4.7K
J 2
(-2600 2300);
DISPLAY 0.510638 (-2600 2300);
PAINT SKYBLUE (-2600 2300);
FORCEPROP 1 LAST TOLERANCE 1%
J 2
(-2600 2250);
DISPLAY 0.510638 (-2600 2250);
PAINT SKYBLUE (-2600 2250);
FORCEPROP 2 LAST CDS_LIB pure_quanta
J 0
(-2575 2250);
DISPLAY INVISIBLE (-2575 2250);
FORCEPROP 1 LAST PATH I172
J 0
(-2525 2425);
DISPLAY 0.978723 (-2525 2425);
PAINT WHITE (-2525 2425);
DISPLAY INVISIBLE (-2525 2425);
FORCEPROP 1 LAST PART_NUMBER CS24702FB06
J 0
(-2535 2125);
DISPLAY 0.510638 (-2535 2125);
PAINT WHITE (-2535 2125);
DISPLAY INVISIBLE (-2535 2125);
FORCEPROP 1 LAST LOCATION R11
J 2
(-2600 2350);
DISPLAY 0.702128 (-2600 2350);
PAINT YELLOW (-2600 2350);
FORCEPROP 1 LASTPIN (-2575 2350) $PN 1
J 0
(-2570 2312);
DISPLAY 0.787234 (-2570 2312);
PAINT MONO (-2570 2312);
FORCEPROP 1 LASTPIN (-2575 2150) $PN 2
J 0
(-2570 2160);
DISPLAY 0.787234 (-2570 2160);
PAINT MONO (-2570 2160);
FORCEPROP 0 LAST $SEC 1
J 0
(-2600 2400);
DISPLAY 0.680851 (-2600 2400);
PAINT MONO (-2600 2400);
DISPLAY INVISIBLE (-2600 2400);
FORCEPROP 0 LAST CDS_SEC 1
J 0
(-2600 2400);
DISPLAY 0.680851 (-2600 2400);
DISPLAY INVISIBLE (-2600 2400);
FORCEADD Q_RES..2
(2975 3925);
FORCEPROP 1 LAST VALUE 4.7K
J 2
(2950 3975);
DISPLAY 0.510638 (2950 3975);
PAINT SKYBLUE (2950 3975);
FORCEPROP 1 LAST MATERIAL CHIP
J 2
(2950 3825);
DISPLAY 0.510638 (2950 3825);
PAINT SKYBLUE (2950 3825);
FORCEPROP 1 LAST WATTAGE 1/16W
J 2
(2950 3875);
DISPLAY 0.510638 (2950 3875);
PAINT SKYBLUE (2950 3875);
FORCEPROP 1 LAST TOLERANCE 1%
J 2
(2950 3925);
DISPLAY 0.510638 (2950 3925);
PAINT SKYBLUE (2950 3925);
FORCEPROP 1 LAST PACK_TYPE 0402LF
J 2
(2950 3775);
DISPLAY 0.510638 (2950 3775);
PAINT SKYBLUE (2950 3775);
FORCEPROP 2 LAST CDS_LIB pure_quanta
J 0
(2975 3925);
DISPLAY INVISIBLE (2975 3925);
FORCEPROP 1 LAST PATH I173
J 0
(3025 4100);
DISPLAY 0.978723 (3025 4100);
PAINT WHITE (3025 4100);
DISPLAY INVISIBLE (3025 4100);
FORCEPROP 1 LAST PART_NUMBER CS24702FB06
J 0
(3015 3800);
DISPLAY 0.510638 (3015 3800);
PAINT WHITE (3015 3800);
DISPLAY INVISIBLE (3015 3800);
FORCEPROP 1 LAST LOCATION R557
J 2
(2950 4025);
DISPLAY 0.702128 (2950 4025);
PAINT YELLOW (2950 4025);
FORCEPROP 1 LASTPIN (2975 4025) $PN 1
J 0
(2980 3987);
DISPLAY 0.787234 (2980 3987);
PAINT MONO (2980 3987);
FORCEPROP 1 LASTPIN (2975 3825) $PN 2
J 0
(2980 3835);
DISPLAY 0.787234 (2980 3835);
PAINT MONO (2980 3835);
FORCEPROP 0 LAST $SEC 1
J 0
(2950 4075);
DISPLAY 0.680851 (2950 4075);
PAINT MONO (2950 4075);
DISPLAY INVISIBLE (2950 4075);
FORCEPROP 0 LAST CDS_SEC 1
J 0
(2950 4075);
DISPLAY 0.680851 (2950 4075);
DISPLAY INVISIBLE (2950 4075);
FORCEADD Q_RES..2
(2850 3925);
FORCEPROP 1 LAST VALUE 4.7K
J 2
(2825 3975);
DISPLAY 0.510638 (2825 3975);
PAINT SKYBLUE (2825 3975);
FORCEPROP 1 LAST TOLERANCE 1%
J 2
(2825 3925);
DISPLAY 0.510638 (2825 3925);
PAINT SKYBLUE (2825 3925);
FORCEPROP 1 LAST MATERIAL CHIP
J 2
(2825 3825);
DISPLAY 0.510638 (2825 3825);
PAINT SKYBLUE (2825 3825);
FORCEPROP 1 LAST WATTAGE 1/16W
J 2
(2825 3875);
DISPLAY 0.510638 (2825 3875);
PAINT SKYBLUE (2825 3875);
FORCEPROP 1 LAST PACK_TYPE 0402LF
J 2
(2825 3775);
DISPLAY 0.510638 (2825 3775);
PAINT SKYBLUE (2825 3775);
FORCEPROP 2 LAST CDS_LIB pure_quanta
J 0
(2850 3925);
DISPLAY INVISIBLE (2850 3925);
FORCEPROP 1 LAST PATH I174
J 0
(2900 4100);
DISPLAY 0.978723 (2900 4100);
PAINT WHITE (2900 4100);
DISPLAY INVISIBLE (2900 4100);
FORCEPROP 1 LAST PART_NUMBER CS24702FB06
J 0
(2890 3800);
DISPLAY 0.510638 (2890 3800);
PAINT WHITE (2890 3800);
DISPLAY INVISIBLE (2890 3800);
FORCEPROP 1 LAST LOCATION R558
J 2
(2825 4025);
DISPLAY 0.702128 (2825 4025);
PAINT YELLOW (2825 4025);
FORCEPROP 1 LASTPIN (2850 4025) $PN 1
J 0
(2855 3987);
DISPLAY 0.787234 (2855 3987);
PAINT MONO (2855 3987);
FORCEPROP 1 LASTPIN (2850 3825) $PN 2
J 0
(2855 3835);
DISPLAY 0.787234 (2855 3835);
PAINT MONO (2855 3835);
FORCEPROP 0 LAST $SEC 1
J 0
(2825 4075);
DISPLAY 0.680851 (2825 4075);
PAINT MONO (2825 4075);
DISPLAY INVISIBLE (2825 4075);
FORCEPROP 0 LAST CDS_SEC 1
J 0
(2825 4075);
DISPLAY 0.680851 (2825 4075);
DISPLAY INVISIBLE (2825 4075);
FORCEADD Q_RES..1
(3500 2700);
FORCEPROP 1 LAST VALUE 33.2
J 2
(3700 2700);
DISPLAY 0.510638 (3700 2700);
PAINT SKYBLUE (3700 2700);
FORCEPROP 1 LAST MATERIAL CHIP
J 0
(3600 2675);
DISPLAY 0.510638 (3600 2675);
PAINT SKYBLUE (3600 2675);
FORCEPROP 1 LAST TOLERANCE 1%
J 0
(3500 2600);
DISPLAY 0.510638 (3500 2600);
PAINT SKYBLUE (3500 2600);
DISPLAY INVISIBLE (3500 2600);
FORCEPROP 1 LAST PART_NUMBER CS03322FB03
J 0
(3450 2800);
DISPLAY 0.510638 (3450 2800);
PAINT WHITE (3450 2800);
DISPLAY INVISIBLE (3450 2800);
FORCEPROP 1 LAST PACK_TYPE 0402LF
J 0
(3750 2550);
DISPLAY 0.510638 (3750 2550);
PAINT SKYBLUE (3750 2550);
DISPLAY INVISIBLE (3750 2550);
FORCEPROP 1 LAST WATTAGE 1/16W
J 2
(3475 2550);
DISPLAY 0.510638 (3475 2550);
PAINT SKYBLUE (3475 2550);
DISPLAY INVISIBLE (3475 2550);
FORCEPROP 1 LAST PATH I175
J 0
(3450 2850);
DISPLAY 0.978723 (3450 2850);
PAINT WHITE (3450 2850);
DISPLAY INVISIBLE (3450 2850);
FORCEPROP 2 LAST CDS_LIB pure_quanta
J 0
(3500 2700);
DISPLAY INVISIBLE (3500 2700);
FORCEPROP 1 LAST LOCATION R553
J 0
(3275 2700);
DISPLAY 0.702128 (3275 2700);
PAINT YELLOW (3275 2700);
FORCEPROP 1 LASTPIN (3400 2700) $PN 1
J 0
(3412 2712);
DISPLAY 0.787234 (3412 2712);
PAINT MONO (3412 2712);
FORCEPROP 1 LASTPIN (3600 2700) $PN 2
J 0
(3562 2712);
DISPLAY 0.787234 (3562 2712);
PAINT MONO (3562 2712);
FORCEPROP 0 LAST $SEC 1
J 0
(3350 2750);
DISPLAY 0.680851 (3350 2750);
PAINT MONO (3350 2750);
DISPLAY INVISIBLE (3350 2750);
FORCEPROP 0 LAST CDS_SEC 1
J 0
(3350 2750);
DISPLAY 0.680851 (3350 2750);
DISPLAY INVISIBLE (3350 2750);
FORCEADD Q_RES..1
(3500 2750);
FORCEPROP 1 LAST VALUE 33.2
J 2
(3700 2750);
DISPLAY 0.510638 (3700 2750);
PAINT SKYBLUE (3700 2750);
FORCEPROP 1 LAST MATERIAL CHIP
J 0
(3600 2725);
DISPLAY 0.510638 (3600 2725);
PAINT SKYBLUE (3600 2725);
FORCEPROP 2 LAST CDS_LIB pure_quanta
J 0
(3500 2750);
DISPLAY INVISIBLE (3500 2750);
FORCEPROP 1 LAST PATH I176
J 0
(3450 2900);
DISPLAY 0.978723 (3450 2900);
PAINT WHITE (3450 2900);
DISPLAY INVISIBLE (3450 2900);
FORCEPROP 1 LAST WATTAGE 1/16W
J 2
(3475 2600);
DISPLAY 0.510638 (3475 2600);
PAINT SKYBLUE (3475 2600);
DISPLAY INVISIBLE (3475 2600);
FORCEPROP 1 LAST PACK_TYPE 0402LF
J 0
(3750 2600);
DISPLAY 0.510638 (3750 2600);
PAINT SKYBLUE (3750 2600);
DISPLAY INVISIBLE (3750 2600);
FORCEPROP 1 LAST PART_NUMBER CS03322FB03
J 0
(3450 2850);
DISPLAY 0.510638 (3450 2850);
PAINT WHITE (3450 2850);
DISPLAY INVISIBLE (3450 2850);
FORCEPROP 1 LAST TOLERANCE 1%
J 0
(3500 2650);
DISPLAY 0.510638 (3500 2650);
PAINT SKYBLUE (3500 2650);
DISPLAY INVISIBLE (3500 2650);
FORCEPROP 1 LAST LOCATION R547
J 0
(3275 2750);
DISPLAY 0.702128 (3275 2750);
PAINT YELLOW (3275 2750);
FORCEPROP 1 LASTPIN (3400 2750) $PN 1
J 0
(3412 2762);
DISPLAY 0.787234 (3412 2762);
PAINT MONO (3412 2762);
FORCEPROP 1 LASTPIN (3600 2750) $PN 2
J 0
(3562 2762);
DISPLAY 0.787234 (3562 2762);
PAINT MONO (3562 2762);
FORCEPROP 0 LAST $SEC 1
J 0
(3350 2800);
DISPLAY 0.680851 (3350 2800);
PAINT MONO (3350 2800);
DISPLAY INVISIBLE (3350 2800);
FORCEPROP 0 LAST CDS_SEC 1
J 0
(3350 2800);
DISPLAY 0.680851 (3350 2800);
DISPLAY INVISIBLE (3350 2800);
FORCEADD Q_RES..1
(3500 2850);
FORCEPROP 1 LAST MATERIAL CHIP
J 0
(3600 2825);
DISPLAY 0.510638 (3600 2825);
PAINT SKYBLUE (3600 2825);
FORCEPROP 1 LAST VALUE 33.2
J 2
(3700 2850);
DISPLAY 0.510638 (3700 2850);
PAINT SKYBLUE (3700 2850);
FORCEPROP 2 LAST CDS_LIB pure_quanta
J 0
(3500 2850);
DISPLAY INVISIBLE (3500 2850);
FORCEPROP 1 LAST PATH I177
J 0
(3450 3000);
DISPLAY 0.978723 (3450 3000);
PAINT WHITE (3450 3000);
DISPLAY INVISIBLE (3450 3000);
FORCEPROP 1 LAST WATTAGE 1/16W
J 2
(3475 2700);
DISPLAY 0.510638 (3475 2700);
PAINT SKYBLUE (3475 2700);
DISPLAY INVISIBLE (3475 2700);
FORCEPROP 1 LAST PACK_TYPE 0402LF
J 0
(3750 2700);
DISPLAY 0.510638 (3750 2700);
PAINT SKYBLUE (3750 2700);
DISPLAY INVISIBLE (3750 2700);
FORCEPROP 1 LAST PART_NUMBER CS03322FB03
J 0
(3450 2950);
DISPLAY 0.510638 (3450 2950);
PAINT WHITE (3450 2950);
DISPLAY INVISIBLE (3450 2950);
FORCEPROP 1 LAST TOLERANCE 1%
J 0
(3500 2750);
DISPLAY 0.510638 (3500 2750);
PAINT SKYBLUE (3500 2750);
DISPLAY INVISIBLE (3500 2750);
FORCEPROP 1 LAST LOCATION R549
J 0
(3275 2850);
DISPLAY 0.702128 (3275 2850);
PAINT YELLOW (3275 2850);
FORCEPROP 1 LASTPIN (3400 2850) $PN 1
J 0
(3412 2862);
DISPLAY 0.787234 (3412 2862);
PAINT MONO (3412 2862);
FORCEPROP 1 LASTPIN (3600 2850) $PN 2
J 0
(3562 2862);
DISPLAY 0.787234 (3562 2862);
PAINT MONO (3562 2862);
FORCEPROP 0 LAST $SEC 1
J 0
(3350 2900);
DISPLAY 0.680851 (3350 2900);
PAINT MONO (3350 2900);
DISPLAY INVISIBLE (3350 2900);
FORCEPROP 0 LAST CDS_SEC 1
J 0
(3350 2900);
DISPLAY 0.680851 (3350 2900);
DISPLAY INVISIBLE (3350 2900);
FORCEADD Q_RES..1
(3500 2950);
FORCEPROP 1 LAST VALUE 33.2
J 2
(3700 2950);
DISPLAY 0.510638 (3700 2950);
PAINT SKYBLUE (3700 2950);
FORCEPROP 1 LAST MATERIAL CHIP
J 0
(3600 2925);
DISPLAY 0.510638 (3600 2925);
PAINT SKYBLUE (3600 2925);
FORCEPROP 2 LAST CDS_LIB pure_quanta
J 0
(3500 2950);
DISPLAY INVISIBLE (3500 2950);
FORCEPROP 1 LAST PATH I178
J 0
(3450 3100);
DISPLAY 0.978723 (3450 3100);
PAINT WHITE (3450 3100);
DISPLAY INVISIBLE (3450 3100);
FORCEPROP 1 LAST WATTAGE 1/16W
J 2
(3475 2800);
DISPLAY 0.510638 (3475 2800);
PAINT SKYBLUE (3475 2800);
DISPLAY INVISIBLE (3475 2800);
FORCEPROP 1 LAST PACK_TYPE 0402LF
J 0
(3750 2800);
DISPLAY 0.510638 (3750 2800);
PAINT SKYBLUE (3750 2800);
DISPLAY INVISIBLE (3750 2800);
FORCEPROP 1 LAST PART_NUMBER CS03322FB03
J 0
(3450 3050);
DISPLAY 0.510638 (3450 3050);
PAINT WHITE (3450 3050);
DISPLAY INVISIBLE (3450 3050);
FORCEPROP 1 LAST TOLERANCE 1%
J 0
(3500 2850);
DISPLAY 0.510638 (3500 2850);
PAINT SKYBLUE (3500 2850);
DISPLAY INVISIBLE (3500 2850);
FORCEPROP 1 LAST LOCATION R550
J 0
(3275 2950);
DISPLAY 0.702128 (3275 2950);
PAINT YELLOW (3275 2950);
FORCEPROP 1 LASTPIN (3400 2950) $PN 1
J 0
(3412 2962);
DISPLAY 0.787234 (3412 2962);
PAINT MONO (3412 2962);
FORCEPROP 1 LASTPIN (3600 2950) $PN 2
J 0
(3562 2962);
DISPLAY 0.787234 (3562 2962);
PAINT MONO (3562 2962);
FORCEPROP 0 LAST $SEC 1
J 0
(3350 3000);
DISPLAY 0.680851 (3350 3000);
PAINT MONO (3350 3000);
DISPLAY INVISIBLE (3350 3000);
FORCEPROP 0 LAST CDS_SEC 1
J 0
(3350 3000);
DISPLAY 0.680851 (3350 3000);
DISPLAY INVISIBLE (3350 3000);
FORCEADD Q_RES..1
(3500 3000);
FORCEPROP 1 LAST MATERIAL CHIP
J 0
(3600 2975);
DISPLAY 0.510638 (3600 2975);
PAINT SKYBLUE (3600 2975);
FORCEPROP 1 LAST VALUE 33.2
J 2
(3700 3000);
DISPLAY 0.510638 (3700 3000);
PAINT SKYBLUE (3700 3000);
FORCEPROP 2 LAST CDS_LIB pure_quanta
J 0
(3500 3000);
DISPLAY INVISIBLE (3500 3000);
FORCEPROP 1 LAST PATH I179
J 0
(3450 3150);
DISPLAY 0.978723 (3450 3150);
PAINT WHITE (3450 3150);
DISPLAY INVISIBLE (3450 3150);
FORCEPROP 1 LAST TOLERANCE 1%
J 0
(3500 2900);
DISPLAY 0.510638 (3500 2900);
PAINT SKYBLUE (3500 2900);
DISPLAY INVISIBLE (3500 2900);
FORCEPROP 1 LAST PART_NUMBER CS03322FB03
J 0
(3450 3100);
DISPLAY 0.510638 (3450 3100);
PAINT WHITE (3450 3100);
DISPLAY INVISIBLE (3450 3100);
FORCEPROP 1 LAST PACK_TYPE 0402LF
J 0
(3750 2850);
DISPLAY 0.510638 (3750 2850);
PAINT SKYBLUE (3750 2850);
DISPLAY INVISIBLE (3750 2850);
FORCEPROP 1 LAST WATTAGE 1/16W
J 2
(3475 2850);
DISPLAY 0.510638 (3475 2850);
PAINT SKYBLUE (3475 2850);
DISPLAY INVISIBLE (3475 2850);
FORCEPROP 1 LAST LOCATION R552
J 0
(3275 3000);
DISPLAY 0.702128 (3275 3000);
PAINT YELLOW (3275 3000);
FORCEPROP 1 LASTPIN (3400 3000) $PN 1
J 0
(3412 3012);
DISPLAY 0.787234 (3412 3012);
PAINT MONO (3412 3012);
FORCEPROP 1 LASTPIN (3600 3000) $PN 2
J 0
(3562 3012);
DISPLAY 0.787234 (3562 3012);
PAINT MONO (3562 3012);
FORCEPROP 0 LAST $SEC 1
J 0
(3350 3050);
DISPLAY 0.680851 (3350 3050);
PAINT MONO (3350 3050);
DISPLAY INVISIBLE (3350 3050);
FORCEPROP 0 LAST CDS_SEC 1
J 0
(3350 3050);
DISPLAY 0.680851 (3350 3050);
DISPLAY INVISIBLE (3350 3050);
FORCEADD Q_RES..1
(3500 3100);
FORCEPROP 1 LAST MATERIAL CHIP
J 0
(3600 3075);
DISPLAY 0.510638 (3600 3075);
PAINT SKYBLUE (3600 3075);
FORCEPROP 1 LAST VALUE 33.2
J 2
(3700 3100);
DISPLAY 0.510638 (3700 3100);
PAINT SKYBLUE (3700 3100);
FORCEPROP 1 LAST TOLERANCE 1%
J 0
(3500 3000);
DISPLAY 0.510638 (3500 3000);
PAINT SKYBLUE (3500 3000);
DISPLAY INVISIBLE (3500 3000);
FORCEPROP 1 LAST PART_NUMBER CS03322FB03
J 0
(3450 3200);
DISPLAY 0.510638 (3450 3200);
PAINT WHITE (3450 3200);
DISPLAY INVISIBLE (3450 3200);
FORCEPROP 1 LAST PACK_TYPE 0402LF
J 0
(3750 2950);
DISPLAY 0.510638 (3750 2950);
PAINT SKYBLUE (3750 2950);
DISPLAY INVISIBLE (3750 2950);
FORCEPROP 1 LAST WATTAGE 1/16W
J 2
(3475 2950);
DISPLAY 0.510638 (3475 2950);
PAINT SKYBLUE (3475 2950);
DISPLAY INVISIBLE (3475 2950);
FORCEPROP 1 LAST PATH I180
J 0
(3450 3250);
DISPLAY 0.978723 (3450 3250);
PAINT WHITE (3450 3250);
DISPLAY INVISIBLE (3450 3250);
FORCEPROP 2 LAST CDS_LIB pure_quanta
J 0
(3500 3100);
DISPLAY INVISIBLE (3500 3100);
FORCEPROP 1 LAST LOCATION R562
J 0
(3275 3100);
DISPLAY 0.702128 (3275 3100);
PAINT YELLOW (3275 3100);
FORCEPROP 1 LASTPIN (3400 3100) $PN 1
J 0
(3412 3112);
DISPLAY 0.787234 (3412 3112);
PAINT MONO (3412 3112);
FORCEPROP 1 LASTPIN (3600 3100) $PN 2
J 0
(3562 3112);
DISPLAY 0.787234 (3562 3112);
PAINT MONO (3562 3112);
FORCEPROP 0 LAST $SEC 1
J 0
(3350 3150);
DISPLAY 0.680851 (3350 3150);
PAINT MONO (3350 3150);
DISPLAY INVISIBLE (3350 3150);
FORCEPROP 0 LAST CDS_SEC 1
J 0
(3350 3150);
DISPLAY 0.680851 (3350 3150);
DISPLAY INVISIBLE (3350 3150);
FORCEADD Q_RES..1
(3500 3150);
FORCEPROP 1 LAST MATERIAL EMPTY
J 0
(3600 3125);
DISPLAY 0.510638 (3600 3125);
PAINT RED (3600 3125);
FORCEPROP 1 LAST VALUE 33.2
J 2
(3700 3150);
DISPLAY 0.510638 (3700 3150);
PAINT SKYBLUE (3700 3150);
FORCEPROP 2 LAST CDS_LIB pure_quanta
J 0
(3500 3150);
DISPLAY INVISIBLE (3500 3150);
FORCEPROP 1 LAST PATH I181
J 0
(3450 3300);
DISPLAY 0.978723 (3450 3300);
PAINT WHITE (3450 3300);
DISPLAY INVISIBLE (3450 3300);
FORCEPROP 1 LAST WATTAGE 1/16W
J 2
(3475 3000);
DISPLAY 0.510638 (3475 3000);
PAINT SKYBLUE (3475 3000);
DISPLAY INVISIBLE (3475 3000);
FORCEPROP 1 LAST PACK_TYPE 0402LF
J 0
(3750 3000);
DISPLAY 0.510638 (3750 3000);
PAINT SKYBLUE (3750 3000);
DISPLAY INVISIBLE (3750 3000);
FORCEPROP 1 LAST PART_NUMBER CS03322FB03
J 0
(3450 3250);
DISPLAY 0.510638 (3450 3250);
PAINT WHITE (3450 3250);
DISPLAY INVISIBLE (3450 3250);
FORCEPROP 1 LAST TOLERANCE 1%
J 0
(3500 3050);
DISPLAY 0.510638 (3500 3050);
PAINT SKYBLUE (3500 3050);
DISPLAY INVISIBLE (3500 3050);
FORCEPROP 1 LAST LOCATION R561
J 0
(3275 3150);
DISPLAY 0.702128 (3275 3150);
PAINT YELLOW (3275 3150);
FORCEPROP 1 LASTPIN (3400 3150) $PN 1
J 0
(3412 3162);
DISPLAY 0.787234 (3412 3162);
PAINT MONO (3412 3162);
FORCEPROP 1 LASTPIN (3600 3150) $PN 2
J 0
(3562 3162);
DISPLAY 0.787234 (3562 3162);
PAINT MONO (3562 3162);
FORCEPROP 0 LAST $SEC 1
J 0
(3350 3200);
DISPLAY 0.680851 (3350 3200);
PAINT MONO (3350 3200);
DISPLAY INVISIBLE (3350 3200);
FORCEPROP 0 LAST CDS_SEC 1
J 0
(3350 3200);
DISPLAY 0.680851 (3350 3200);
DISPLAY INVISIBLE (3350 3200);
FORCEADD Q_RES..2
(3100 3925);
FORCEPROP 1 LAST MATERIAL EMPTY
J 2
(3075 3825);
DISPLAY 0.510638 (3075 3825);
PAINT RED (3075 3825);
FORCEPROP 1 LAST WATTAGE 1/16W
J 2
(3075 3875);
DISPLAY 0.510638 (3075 3875);
PAINT SKYBLUE (3075 3875);
FORCEPROP 1 LAST PACK_TYPE 0402LF
J 2
(3075 3775);
DISPLAY 0.510638 (3075 3775);
PAINT SKYBLUE (3075 3775);
FORCEPROP 1 LAST VALUE 4.7K
J 2
(3075 3975);
DISPLAY 0.510638 (3075 3975);
PAINT SKYBLUE (3075 3975);
FORCEPROP 1 LAST TOLERANCE 1%
J 2
(3075 3925);
DISPLAY 0.510638 (3075 3925);
PAINT SKYBLUE (3075 3925);
FORCEPROP 2 LAST CDS_LIB pure_quanta
J 0
(3100 3925);
DISPLAY INVISIBLE (3100 3925);
FORCEPROP 1 LAST PATH I182
J 0
(3150 4100);
DISPLAY 0.978723 (3150 4100);
PAINT WHITE (3150 4100);
DISPLAY INVISIBLE (3150 4100);
FORCEPROP 1 LAST PART_NUMBER CS24702FB06
J 0
(3140 3800);
DISPLAY 0.510638 (3140 3800);
PAINT WHITE (3140 3800);
DISPLAY INVISIBLE (3140 3800);
FORCEPROP 1 LAST LOCATION R90
J 2
(3075 4025);
DISPLAY 0.702128 (3075 4025);
PAINT YELLOW (3075 4025);
FORCEPROP 1 LASTPIN (3100 4025) $PN 1
J 0
(3105 3987);
DISPLAY 0.787234 (3105 3987);
PAINT MONO (3105 3987);
FORCEPROP 1 LASTPIN (3100 3825) $PN 2
J 0
(3105 3835);
DISPLAY 0.787234 (3105 3835);
PAINT MONO (3105 3835);
FORCEPROP 0 LAST $SEC 1
J 0
(3075 4075);
DISPLAY 0.680851 (3075 4075);
PAINT MONO (3075 4075);
DISPLAY INVISIBLE (3075 4075);
FORCEPROP 0 LAST CDS_SEC 1
J 0
(3075 4075);
DISPLAY 0.680851 (3075 4075);
DISPLAY INVISIBLE (3075 4075);
FORCEADD UNIVERSAL_GND..1
(4200 -1400);
FORCEPROP 3 LASTPIN (4200 -1350) SIG_NAME GND\g
J 0
(4210 -1340);
DISPLAY 0.659574 (4210 -1340);
PAINT MONO (4210 -1340);
DISPLAY INVISIBLE (4210 -1340);
FORCEPROP 1 LAST PATH I20
J 0
(4275 -1400);
DISPLAY 0.872340 (4275 -1400);
PAINT AQUA (4275 -1400);
DISPLAY INVISIBLE (4275 -1400);
FORCEPROP 2 LAST CDS_LIB logical_power
J 0
(4200 -1400);
DISPLAY INVISIBLE (4200 -1400);
FORCEPROP 1 LAST HDL_POWER GND
J 1
(4225 -1475);
DISPLAY 0.702128 (4225 -1475);
PAINT GREEN (4225 -1475);
DISPLAY INVISIBLE (4225 -1475);
FORCEADD Q_CAP..1
(4775 -600);
FORCEPROP 1 LAST VALUE 0.1UF
J 0
(4825 -550);
DISPLAY 0.510638 (4825 -550);
PAINT SKYBLUE (4825 -550);
FORCEPROP 1 LAST MATERIAL EMPTY
J 0
(4825 -700);
DISPLAY 0.510638 (4825 -700);
PAINT RED (4825 -700);
FORCEPROP 1 LAST TOLERANCE 10%
J 0
(4825 -650);
DISPLAY 0.510638 (4825 -650);
PAINT SKYBLUE (4825 -650);
FORCEPROP 1 LAST PACK_TYPE 0402
J 0
(4825 -750);
DISPLAY 0.510638 (4825 -750);
PAINT SKYBLUE (4825 -750);
FORCEPROP 1 LAST VOLTAGE 25V
J 0
(4825 -600);
DISPLAY 0.510638 (4825 -600);
PAINT SKYBLUE (4825 -600);
FORCEPROP 1 LAST PATH I21
J 0
(4825 -450);
DISPLAY 0.978723 (4825 -450);
PAINT WHITE (4825 -450);
DISPLAY INVISIBLE (4825 -450);
FORCEPROP 1 LAST PART_NUMBER CH4104K1B00
R 3
J 0
(4675 -300);
DISPLAY 0.510638 (4675 -300);
PAINT WHITE (4675 -300);
DISPLAY INVISIBLE (4675 -300);
FORCEPROP 2 LAST CDS_LIB pure_quanta
J 0
(4775 -600);
DISPLAY INVISIBLE (4775 -600);
FORCEPROP 1 LAST LOCATION C228
J 0
(4825 -500);
DISPLAY 0.702128 (4825 -500);
PAINT YELLOW (4825 -500);
FORCEPROP 1 LASTPIN (4775 -500) $PN 1
J 0
(4785 -520);
DISPLAY 0.808511 (4785 -520);
PAINT WHITE (4785 -520);
FORCEPROP 1 LASTPIN (4775 -700) $PN 2
J 0
(4785 -720);
DISPLAY 0.808511 (4785 -720);
PAINT WHITE (4785 -720);
FORCEPROP 0 LAST $SEC 1
J 0
(4825 -450);
DISPLAY 0.680851 (4825 -450);
PAINT MONO (4825 -450);
DISPLAY INVISIBLE (4825 -450);
FORCEPROP 0 LAST CDS_SEC 1
J 0
(4825 -450);
DISPLAY 1.021277 (4825 -450);
DISPLAY INVISIBLE (4825 -450);
FORCEADD OFFPAGE..4
R 2
(-650 1950);
FORCEPROP 2 LAST $XR0 13 
J 0
(-901 1950);
DISPLAY 0.638298 (-901 1950);
PAINT MONO (-901 1950);
FORCEPROP 2 LAST $XR1 21 
J 0
(-991 1950);
DISPLAY 0.638298 (-991 1950);
PAINT MONO (-991 1950);
FORCEPROP 1 LAST COMMENT_BODY TRUE
J 2
(-625 1850);
DISPLAY 0.872340 (-625 1850);
PAINT GREEN (-625 1850);
DISPLAY INVISIBLE (-625 1850);
FORCEPROP 1 LAST OFFPAGE TRUE
J 2
(-975 1825);
DISPLAY 0.872340 (-975 1825);
DISPLAY INVISIBLE (-975 1825);
FORCEPROP 2 LAST CDS_LIB standard
J 0
(-650 1950);
DISPLAY INVISIBLE (-650 1950);
FORCEPROP 2 LAST PATH I25
J 0
(-925 2000);
DISPLAY 0.680851 (-925 2000);
DISPLAY INVISIBLE (-925 2000);
FORCEADD UNIVERSAL_POWER..1
(-2575 2500);
FORCEPROP 3 LASTPIN (-2575 2450) SIG_NAME P3V3_AUX\g
J 0
(-2565 2460);
DISPLAY 0.659574 (-2565 2460);
PAINT MONO (-2565 2460);
DISPLAY INVISIBLE (-2565 2460);
FORCEPROP 1 LAST HDL_POWER P3V3_AUX
J 1
(-2575 2550);
DISPLAY 0.702128 (-2575 2550);
PAINT GREEN (-2575 2550);
FORCEPROP 1 LAST PATH I3
J 0
(-2525 2525);
DISPLAY 0.872340 (-2525 2525);
PAINT AQUA (-2525 2525);
DISPLAY INVISIBLE (-2525 2525);
FORCEPROP 2 LAST CDS_LIB logical_power
J 0
(-2575 2500);
DISPLAY INVISIBLE (-2575 2500);
FORCEADD Q_RES..1
(3250 2250);
FORCEPROP 1 LAST VALUE 33.2
J 2
(3650 2250);
DISPLAY 0.510638 (3650 2250);
PAINT SKYBLUE (3650 2250);
FORCEPROP 1 LAST MATERIAL EMPTY
J 0
(3400 2250);
DISPLAY 0.510638 (3400 2250);
PAINT RED (3400 2250);
FORCEPROP 1 LAST PART_NUMBER CS03322FB03
J 0
(3050 2825);
DISPLAY 0.510638 (3050 2825);
PAINT WHITE (3050 2825);
DISPLAY INVISIBLE (3050 2825);
FORCEPROP 1 LAST PATH I33
J 0
(3200 2400);
DISPLAY 0.978723 (3200 2400);
PAINT WHITE (3200 2400);
DISPLAY INVISIBLE (3200 2400);
FORCEPROP 2 LAST CDS_LIB pure_quanta
J 0
(3250 2250);
DISPLAY INVISIBLE (3250 2250);
FORCEPROP 1 LAST WATTAGE 1/16W
J 2
(3225 2100);
DISPLAY 0.510638 (3225 2100);
PAINT SKYBLUE (3225 2100);
DISPLAY INVISIBLE (3225 2100);
FORCEPROP 1 LAST PACK_TYPE 0402LF
J 0
(3500 2100);
DISPLAY 0.510638 (3500 2100);
PAINT SKYBLUE (3500 2100);
DISPLAY INVISIBLE (3500 2100);
FORCEPROP 1 LAST TOLERANCE 1%
J 0
(3250 2150);
DISPLAY 0.510638 (3250 2150);
PAINT SKYBLUE (3250 2150);
DISPLAY INVISIBLE (3250 2150);
FORCEPROP 1 LAST LOCATION R654
J 0
(3025 2250);
DISPLAY 0.702128 (3025 2250);
PAINT YELLOW (3025 2250);
FORCEPROP 1 LASTPIN (3150 2250) $PN 1
J 0
(3162 2262);
DISPLAY 0.808511 (3162 2262);
PAINT WHITE (3162 2262);
FORCEPROP 1 LASTPIN (3350 2250) $PN 2
J 0
(3312 2262);
DISPLAY 0.808511 (3312 2262);
PAINT WHITE (3312 2262);
FORCEPROP 0 LAST $SEC 1
J 0
(3825 2300);
DISPLAY 0.680851 (3825 2300);
PAINT MONO (3825 2300);
DISPLAY INVISIBLE (3825 2300);
FORCEPROP 0 LAST CDS_SEC 1
J 0
(3625 2300);
DISPLAY 0.680851 (3625 2300);
DISPLAY INVISIBLE (3625 2300);
FORCEADD Q_RES..1
(3250 2150);
FORCEPROP 1 LAST VALUE 33.2
J 2
(3650 2150);
DISPLAY 0.510638 (3650 2150);
PAINT SKYBLUE (3650 2150);
FORCEPROP 1 LAST MATERIAL EMPTY
J 0
(3400 2150);
DISPLAY 0.510638 (3400 2150);
PAINT RED (3400 2150);
FORCEPROP 1 LAST PACK_TYPE 0402LF
J 0
(3500 2000);
DISPLAY 0.510638 (3500 2000);
PAINT SKYBLUE (3500 2000);
DISPLAY INVISIBLE (3500 2000);
FORCEPROP 1 LAST WATTAGE 1/16W
J 2
(3225 2000);
DISPLAY 0.510638 (3225 2000);
PAINT SKYBLUE (3225 2000);
DISPLAY INVISIBLE (3225 2000);
FORCEPROP 2 LAST CDS_LIB pure_quanta
J 0
(3250 2150);
DISPLAY INVISIBLE (3250 2150);
FORCEPROP 1 LAST PATH I35
J 0
(3200 2300);
DISPLAY 0.978723 (3200 2300);
PAINT WHITE (3200 2300);
DISPLAY INVISIBLE (3200 2300);
FORCEPROP 1 LAST TOLERANCE 1%
J 0
(3250 2050);
DISPLAY 0.510638 (3250 2050);
PAINT SKYBLUE (3250 2050);
DISPLAY INVISIBLE (3250 2050);
FORCEPROP 1 LAST PART_NUMBER CS03322FB03
J 0
(3050 1950);
DISPLAY 0.510638 (3050 1950);
PAINT WHITE (3050 1950);
DISPLAY INVISIBLE (3050 1950);
FORCEPROP 1 LAST LOCATION R48
J 0
(3025 2150);
DISPLAY 0.702128 (3025 2150);
PAINT YELLOW (3025 2150);
FORCEPROP 1 LASTPIN (3150 2150) $PN 1
J 0
(3162 2162);
DISPLAY 0.808511 (3162 2162);
PAINT WHITE (3162 2162);
FORCEPROP 1 LASTPIN (3350 2150) $PN 2
J 0
(3312 2162);
DISPLAY 0.808511 (3312 2162);
PAINT WHITE (3312 2162);
FORCEPROP 0 LAST $SEC 1
J 0
(3825 2200);
DISPLAY 0.680851 (3825 2200);
PAINT MONO (3825 2200);
DISPLAY INVISIBLE (3825 2200);
FORCEPROP 0 LAST CDS_SEC 1
J 0
(3625 2200);
DISPLAY 1.021277 (3625 2200);
DISPLAY INVISIBLE (3625 2200);
FORCEADD Q_RES..1
(3250 1850);
FORCEPROP 1 LAST PART_NUMBER CS03322FB03
J 0
(2900 1900);
DISPLAY 0.510638 (2900 1900);
PAINT WHITE (2900 1900);
FORCEPROP 1 LAST MATERIAL EMPTY
J 0
(3400 1850);
DISPLAY 0.510638 (3400 1850);
PAINT RED (3400 1850);
FORCEPROP 1 LAST VALUE 33.2
J 2
(3775 1850);
DISPLAY 0.510638 (3775 1850);
PAINT SKYBLUE (3775 1850);
FORCEPROP 1 LAST WATTAGE 1/16W
J 2
(3100 1925);
DISPLAY 0.510638 (3100 1925);
PAINT SKYBLUE (3100 1925);
DISPLAY INVISIBLE (3100 1925);
FORCEPROP 1 LAST PACK_TYPE 0402LF
J 0
(3400 1925);
DISPLAY 0.510638 (3400 1925);
PAINT SKYBLUE (3400 1925);
DISPLAY INVISIBLE (3400 1925);
FORCEPROP 1 LAST PATH I42
J 0
(3200 2000);
DISPLAY 0.978723 (3200 2000);
PAINT WHITE (3200 2000);
DISPLAY INVISIBLE (3200 2000);
FORCEPROP 2 LAST CDS_LIB pure_quanta
J 0
(3250 1850);
DISPLAY INVISIBLE (3250 1850);
FORCEPROP 1 LAST TOLERANCE 1%
J 0
(3300 1925);
DISPLAY 0.510638 (3300 1925);
PAINT SKYBLUE (3300 1925);
DISPLAY INVISIBLE (3300 1925);
FORCEPROP 1 LAST LOCATION R649
J 0
(3025 1850);
DISPLAY 0.702128 (3025 1850);
PAINT YELLOW (3025 1850);
FORCEPROP 1 LASTPIN (3150 1850) $PN 1
J 0
(3162 1862);
DISPLAY 0.808511 (3162 1862);
PAINT WHITE (3162 1862);
FORCEPROP 1 LASTPIN (3350 1850) $PN 2
J 0
(3312 1862);
DISPLAY 0.808511 (3312 1862);
PAINT WHITE (3312 1862);
FORCEPROP 0 LAST $SEC 1
J 0
(2950 2200);
DISPLAY 0.680851 (2950 2200);
PAINT MONO (2950 2200);
DISPLAY INVISIBLE (2950 2200);
FORCEPROP 0 LAST CDS_SEC 1
J 0
(3725 1900);
DISPLAY 1.021277 (3725 1900);
DISPLAY INVISIBLE (3725 1900);
FORCEADD Q_RES..1
(3250 1950);
FORCEPROP 1 LAST MATERIAL EMPTY
J 0
(3400 1950);
DISPLAY 0.510638 (3400 1950);
PAINT RED (3400 1950);
FORCEPROP 1 LAST VALUE 33.2
J 2
(3650 1950);
DISPLAY 0.510638 (3650 1950);
PAINT SKYBLUE (3650 1950);
FORCEPROP 1 LAST PACK_TYPE 0402LF
J 0
(3500 1800);
DISPLAY 0.510638 (3500 1800);
PAINT SKYBLUE (3500 1800);
DISPLAY INVISIBLE (3500 1800);
FORCEPROP 1 LAST WATTAGE 1/16W
J 2
(3225 1800);
DISPLAY 0.510638 (3225 1800);
PAINT SKYBLUE (3225 1800);
DISPLAY INVISIBLE (3225 1800);
FORCEPROP 2 LAST CDS_LIB pure_quanta
J 0
(3250 1950);
DISPLAY INVISIBLE (3250 1950);
FORCEPROP 1 LAST PATH I43
J 0
(3200 2100);
DISPLAY 0.978723 (3200 2100);
PAINT WHITE (3200 2100);
DISPLAY INVISIBLE (3200 2100);
FORCEPROP 1 LAST TOLERANCE 1%
J 0
(3250 1850);
DISPLAY 0.510638 (3250 1850);
PAINT SKYBLUE (3250 1850);
DISPLAY INVISIBLE (3250 1850);
FORCEPROP 1 LAST PART_NUMBER CS03322FB03
J 0
(2875 2200);
DISPLAY 0.510638 (2875 2200);
PAINT WHITE (2875 2200);
DISPLAY INVISIBLE (2875 2200);
FORCEPROP 1 LAST LOCATION R648
J 0
(3025 1950);
DISPLAY 0.702128 (3025 1950);
PAINT YELLOW (3025 1950);
FORCEPROP 1 LASTPIN (3150 1950) $PN 1
J 0
(3162 1962);
DISPLAY 0.808511 (3162 1962);
PAINT WHITE (3162 1962);
FORCEPROP 1 LASTPIN (3350 1950) $PN 2
J 0
(3312 1962);
DISPLAY 0.808511 (3312 1962);
PAINT WHITE (3312 1962);
FORCEPROP 0 LAST $SEC 1
J 0
(3825 2000);
DISPLAY 0.680851 (3825 2000);
PAINT MONO (3825 2000);
DISPLAY INVISIBLE (3825 2000);
FORCEPROP 0 LAST CDS_SEC 1
J 0
(3725 2000);
DISPLAY 1.021277 (3725 2000);
DISPLAY INVISIBLE (3725 2000);
FORCEADD Q_RES..1
(3250 2000);
FORCEPROP 1 LAST MATERIAL EMPTY
J 0
(3400 2000);
DISPLAY 0.510638 (3400 2000);
PAINT RED (3400 2000);
FORCEPROP 1 LAST VALUE 33.2
J 2
(3650 2000);
DISPLAY 0.510638 (3650 2000);
PAINT SKYBLUE (3650 2000);
FORCEPROP 1 LAST PATH I45
J 0
(3200 2150);
DISPLAY 0.978723 (3200 2150);
PAINT WHITE (3200 2150);
DISPLAY INVISIBLE (3200 2150);
FORCEPROP 2 LAST CDS_LIB pure_quanta
J 0
(3250 2000);
DISPLAY INVISIBLE (3250 2000);
FORCEPROP 1 LAST WATTAGE 1/16W
J 2
(3225 1850);
DISPLAY 0.510638 (3225 1850);
PAINT SKYBLUE (3225 1850);
DISPLAY INVISIBLE (3225 1850);
FORCEPROP 1 LAST PACK_TYPE 0402LF
J 0
(3500 1850);
DISPLAY 0.510638 (3500 1850);
PAINT SKYBLUE (3500 1850);
DISPLAY INVISIBLE (3500 1850);
FORCEPROP 1 LAST TOLERANCE 1%
J 0
(3250 1900);
DISPLAY 0.510638 (3250 1900);
PAINT SKYBLUE (3250 1900);
DISPLAY INVISIBLE (3250 1900);
FORCEPROP 1 LAST PART_NUMBER CS03322FB03
J 0
(2850 2200);
DISPLAY 0.510638 (2850 2200);
PAINT WHITE (2850 2200);
DISPLAY INVISIBLE (2850 2200);
FORCEPROP 1 LAST LOCATION R647
J 0
(3025 2000);
DISPLAY 0.702128 (3025 2000);
PAINT YELLOW (3025 2000);
FORCEPROP 1 LASTPIN (3150 2000) $PN 1
J 0
(3162 2012);
DISPLAY 0.808511 (3162 2012);
PAINT WHITE (3162 2012);
FORCEPROP 1 LASTPIN (3350 2000) $PN 2
J 0
(3312 2012);
DISPLAY 0.808511 (3312 2012);
PAINT WHITE (3312 2012);
FORCEPROP 0 LAST $SEC 1
J 0
(3825 2050);
DISPLAY 0.680851 (3825 2050);
PAINT MONO (3825 2050);
DISPLAY INVISIBLE (3825 2050);
FORCEPROP 0 LAST CDS_SEC 1
J 0
(3725 2050);
DISPLAY 1.021277 (3725 2050);
DISPLAY INVISIBLE (3725 2050);
FORCEADD Q_RES..1
(3250 2100);
FORCEPROP 1 LAST MATERIAL EMPTY
J 0
(3400 2100);
DISPLAY 0.510638 (3400 2100);
PAINT RED (3400 2100);
FORCEPROP 1 LAST VALUE 33.2
J 2
(3650 2100);
DISPLAY 0.510638 (3650 2100);
PAINT SKYBLUE (3650 2100);
FORCEPROP 1 LAST PATH I46
J 0
(3200 2250);
DISPLAY 0.978723 (3200 2250);
PAINT WHITE (3200 2250);
DISPLAY INVISIBLE (3200 2250);
FORCEPROP 2 LAST CDS_LIB pure_quanta
J 0
(3250 2100);
DISPLAY INVISIBLE (3250 2100);
FORCEPROP 1 LAST WATTAGE 1/16W
J 2
(3225 1950);
DISPLAY 0.510638 (3225 1950);
PAINT SKYBLUE (3225 1950);
DISPLAY INVISIBLE (3225 1950);
FORCEPROP 1 LAST PACK_TYPE 0402LF
J 0
(3500 1950);
DISPLAY 0.510638 (3500 1950);
PAINT SKYBLUE (3500 1950);
DISPLAY INVISIBLE (3500 1950);
FORCEPROP 1 LAST TOLERANCE 1%
J 0
(3250 2000);
DISPLAY 0.510638 (3250 2000);
PAINT SKYBLUE (3250 2000);
DISPLAY INVISIBLE (3250 2000);
FORCEPROP 1 LAST PART_NUMBER CS03322FB03
J 0
(2825 2225);
DISPLAY 0.510638 (2825 2225);
PAINT WHITE (2825 2225);
DISPLAY INVISIBLE (2825 2225);
FORCEPROP 1 LAST LOCATION R532
J 0
(3025 2100);
DISPLAY 0.702128 (3025 2100);
PAINT YELLOW (3025 2100);
FORCEPROP 1 LASTPIN (3150 2100) $PN 1
J 0
(3162 2112);
DISPLAY 0.808511 (3162 2112);
PAINT WHITE (3162 2112);
FORCEPROP 1 LASTPIN (3350 2100) $PN 2
J 0
(3312 2112);
DISPLAY 0.808511 (3312 2112);
PAINT WHITE (3312 2112);
FORCEPROP 0 LAST $SEC 1
J 0
(3825 2150);
DISPLAY 0.680851 (3825 2150);
PAINT MONO (3825 2150);
DISPLAY INVISIBLE (3825 2150);
FORCEPROP 0 LAST CDS_SEC 1
J 0
(2725 2275);
DISPLAY 1.021277 (2725 2275);
DISPLAY INVISIBLE (2725 2275);
FORCEADD UNIVERSAL_POWER..1
(4100 75);
FORCEPROP 3 LASTPIN (4100 25) SIG_NAME P3V3_AUX\g
J 0
(4110 35);
DISPLAY 0.659574 (4110 35);
PAINT MONO (4110 35);
DISPLAY INVISIBLE (4110 35);
FORCEPROP 1 LAST HDL_POWER P3V3_AUX
J 1
(4100 125);
DISPLAY 0.702128 (4100 125);
PAINT GREEN (4100 125);
FORCEPROP 2 LAST CDS_LIB logical_power
J 0
(4100 75);
DISPLAY INVISIBLE (4100 75);
FORCEPROP 1 LAST PATH I47
J 0
(4150 100);
DISPLAY 0.872340 (4150 100);
PAINT AQUA (4150 100);
DISPLAY INVISIBLE (4150 100);
FORCEADD Q_RES..1
(-2475 3975);
FORCEPROP 1 LAST MATERIAL EMPTY
J 0
(-2125 3975);
DISPLAY 0.510638 (-2125 3975);
PAINT RED (-2125 3975);
FORCEPROP 1 LAST VALUE 10K
J 2
(-2200 3975);
DISPLAY 0.510638 (-2200 3975);
PAINT SKYBLUE (-2200 3975);
FORCEPROP 1 LAST PATH I58
J 0
(-2525 4125);
DISPLAY 0.978723 (-2525 4125);
PAINT WHITE (-2525 4125);
DISPLAY INVISIBLE (-2525 4125);
FORCEPROP 2 LAST CDS_LIB pure_quanta
J 0
(-2475 3975);
DISPLAY INVISIBLE (-2475 3975);
FORCEPROP 1 LAST PART_NUMBER TMP_QCS31002FB26
J 0
(-2500 3700);
DISPLAY 0.510638 (-2500 3700);
PAINT WHITE (-2500 3700);
DISPLAY INVISIBLE (-2500 3700);
FORCEPROP 1 LAST TOLERANCE 1%
J 0
(-2475 3875);
DISPLAY 0.510638 (-2475 3875);
PAINT SKYBLUE (-2475 3875);
DISPLAY INVISIBLE (-2475 3875);
FORCEPROP 1 LAST WATTAGE 1/16W
J 2
(-2500 3825);
DISPLAY 0.510638 (-2500 3825);
PAINT SKYBLUE (-2500 3825);
DISPLAY INVISIBLE (-2500 3825);
FORCEPROP 1 LAST PACK_TYPE 0402LF
J 0
(-2225 3825);
DISPLAY 0.510638 (-2225 3825);
PAINT SKYBLUE (-2225 3825);
DISPLAY INVISIBLE (-2225 3825);
FORCEPROP 1 LAST LOCATION R662
J 0
(-2775 3975);
DISPLAY 0.702128 (-2775 3975);
PAINT YELLOW (-2775 3975);
FORCEPROP 1 LASTPIN (-2575 3975) $PN 1
J 0
(-2563 3987);
DISPLAY 0.808511 (-2563 3987);
PAINT WHITE (-2563 3987);
FORCEPROP 1 LASTPIN (-2375 3975) $PN 2
J 0
(-2413 3987);
DISPLAY 0.808511 (-2413 3987);
PAINT WHITE (-2413 3987);
FORCEPROP 0 LAST $SEC 1
J 0
(-2200 4025);
DISPLAY 0.680851 (-2200 4025);
PAINT MONO (-2200 4025);
DISPLAY INVISIBLE (-2200 4025);
FORCEPROP 0 LAST CDS_SEC 1
J 0
(-2200 4025);
DISPLAY 1.021277 (-2200 4025);
DISPLAY INVISIBLE (-2200 4025);
FORCEADD Q_RES..1
(-2475 3925);
FORCEPROP 1 LAST MATERIAL EMPTY
J 0
(-2125 3925);
DISPLAY 0.510638 (-2125 3925);
PAINT RED (-2125 3925);
FORCEPROP 1 LAST VALUE 10K
J 2
(-2200 3925);
DISPLAY 0.510638 (-2200 3925);
PAINT SKYBLUE (-2200 3925);
FORCEPROP 1 LAST PATH I59
J 0
(-2525 4075);
DISPLAY 0.978723 (-2525 4075);
PAINT WHITE (-2525 4075);
DISPLAY INVISIBLE (-2525 4075);
FORCEPROP 2 LAST CDS_LIB pure_quanta
J 0
(-2475 3925);
DISPLAY INVISIBLE (-2475 3925);
FORCEPROP 1 LAST PART_NUMBER TMP_QCS31002FB26
J 0
(-2500 3650);
DISPLAY 0.510638 (-2500 3650);
PAINT WHITE (-2500 3650);
DISPLAY INVISIBLE (-2500 3650);
FORCEPROP 1 LAST TOLERANCE 1%
J 0
(-2475 3825);
DISPLAY 0.510638 (-2475 3825);
PAINT SKYBLUE (-2475 3825);
DISPLAY INVISIBLE (-2475 3825);
FORCEPROP 1 LAST WATTAGE 1/16W
J 2
(-2500 3775);
DISPLAY 0.510638 (-2500 3775);
PAINT SKYBLUE (-2500 3775);
DISPLAY INVISIBLE (-2500 3775);
FORCEPROP 1 LAST PACK_TYPE 0402LF
J 0
(-2225 3775);
DISPLAY 0.510638 (-2225 3775);
PAINT SKYBLUE (-2225 3775);
DISPLAY INVISIBLE (-2225 3775);
FORCEPROP 1 LAST LOCATION R663
J 0
(-2775 3925);
DISPLAY 0.702128 (-2775 3925);
PAINT YELLOW (-2775 3925);
FORCEPROP 1 LASTPIN (-2575 3925) $PN 1
J 0
(-2563 3937);
DISPLAY 0.808511 (-2563 3937);
PAINT WHITE (-2563 3937);
FORCEPROP 1 LASTPIN (-2375 3925) $PN 2
J 0
(-2413 3937);
DISPLAY 0.808511 (-2413 3937);
PAINT WHITE (-2413 3937);
FORCEPROP 0 LAST $SEC 1
J 0
(-2200 3975);
DISPLAY 0.680851 (-2200 3975);
PAINT MONO (-2200 3975);
DISPLAY INVISIBLE (-2200 3975);
FORCEPROP 0 LAST CDS_SEC 1
J 0
(-2200 3975);
DISPLAY 1.021277 (-2200 3975);
DISPLAY INVISIBLE (-2200 3975);
FORCEADD Q_RES..1
(-2475 4025);
FORCEPROP 1 LAST MATERIAL EMPTY
J 0
(-2125 4025);
DISPLAY 0.510638 (-2125 4025);
PAINT RED (-2125 4025);
FORCEPROP 1 LAST VALUE 10K
J 2
(-2200 4025);
DISPLAY 0.510638 (-2200 4025);
PAINT SKYBLUE (-2200 4025);
FORCEPROP 1 LAST PATH I60
J 0
(-2525 4175);
DISPLAY 0.978723 (-2525 4175);
PAINT WHITE (-2525 4175);
DISPLAY INVISIBLE (-2525 4175);
FORCEPROP 2 LAST CDS_LIB pure_quanta
J 0
(-2475 4025);
DISPLAY INVISIBLE (-2475 4025);
FORCEPROP 1 LAST PART_NUMBER TMP_QCS31002FB26
J 0
(-2500 3750);
DISPLAY 0.510638 (-2500 3750);
PAINT WHITE (-2500 3750);
DISPLAY INVISIBLE (-2500 3750);
FORCEPROP 1 LAST TOLERANCE 1%
J 0
(-2475 3925);
DISPLAY 0.510638 (-2475 3925);
PAINT SKYBLUE (-2475 3925);
DISPLAY INVISIBLE (-2475 3925);
FORCEPROP 1 LAST WATTAGE 1/16W
J 2
(-2500 3875);
DISPLAY 0.510638 (-2500 3875);
PAINT SKYBLUE (-2500 3875);
DISPLAY INVISIBLE (-2500 3875);
FORCEPROP 1 LAST PACK_TYPE 0402LF
J 0
(-2225 3875);
DISPLAY 0.510638 (-2225 3875);
PAINT SKYBLUE (-2225 3875);
DISPLAY INVISIBLE (-2225 3875);
FORCEPROP 1 LAST LOCATION R661
J 0
(-2775 4025);
DISPLAY 0.702128 (-2775 4025);
PAINT YELLOW (-2775 4025);
FORCEPROP 1 LASTPIN (-2575 4025) $PN 1
J 0
(-2563 4037);
DISPLAY 0.808511 (-2563 4037);
PAINT WHITE (-2563 4037);
FORCEPROP 1 LASTPIN (-2375 4025) $PN 2
J 0
(-2413 4037);
DISPLAY 0.808511 (-2413 4037);
PAINT WHITE (-2413 4037);
FORCEPROP 0 LAST $SEC 1
J 0
(-2200 4075);
DISPLAY 0.680851 (-2200 4075);
PAINT MONO (-2200 4075);
DISPLAY INVISIBLE (-2200 4075);
FORCEPROP 0 LAST CDS_SEC 1
J 0
(-2200 4075);
DISPLAY 1.021277 (-2200 4075);
DISPLAY INVISIBLE (-2200 4075);
FORCEADD Q_RES..1
(-2475 4075);
FORCEPROP 1 LAST MATERIAL EMPTY
J 0
(-2125 4075);
DISPLAY 0.510638 (-2125 4075);
PAINT RED (-2125 4075);
FORCEPROP 1 LAST VALUE 10K
J 2
(-2200 4075);
DISPLAY 0.510638 (-2200 4075);
PAINT SKYBLUE (-2200 4075);
FORCEPROP 1 LAST PATH I61
J 0
(-2525 4225);
DISPLAY 0.978723 (-2525 4225);
PAINT WHITE (-2525 4225);
DISPLAY INVISIBLE (-2525 4225);
FORCEPROP 2 LAST CDS_LIB pure_quanta
J 0
(-2475 4075);
DISPLAY INVISIBLE (-2475 4075);
FORCEPROP 1 LAST PART_NUMBER TMP_QCS31002FB26
J 0
(-2500 3800);
DISPLAY 0.510638 (-2500 3800);
PAINT WHITE (-2500 3800);
DISPLAY INVISIBLE (-2500 3800);
FORCEPROP 1 LAST TOLERANCE 1%
J 0
(-2475 3975);
DISPLAY 0.510638 (-2475 3975);
PAINT SKYBLUE (-2475 3975);
DISPLAY INVISIBLE (-2475 3975);
FORCEPROP 1 LAST WATTAGE 1/16W
J 2
(-2500 3925);
DISPLAY 0.510638 (-2500 3925);
PAINT SKYBLUE (-2500 3925);
DISPLAY INVISIBLE (-2500 3925);
FORCEPROP 1 LAST PACK_TYPE 0402LF
J 0
(-2225 3925);
DISPLAY 0.510638 (-2225 3925);
PAINT SKYBLUE (-2225 3925);
DISPLAY INVISIBLE (-2225 3925);
FORCEPROP 1 LAST LOCATION R660
J 0
(-2775 4075);
DISPLAY 0.702128 (-2775 4075);
PAINT YELLOW (-2775 4075);
FORCEPROP 1 LASTPIN (-2575 4075) $PN 1
J 0
(-2563 4087);
DISPLAY 0.808511 (-2563 4087);
PAINT WHITE (-2563 4087);
FORCEPROP 1 LASTPIN (-2375 4075) $PN 2
J 0
(-2413 4087);
DISPLAY 0.808511 (-2413 4087);
PAINT WHITE (-2413 4087);
FORCEPROP 0 LAST $SEC 1
J 0
(-2200 4125);
DISPLAY 0.680851 (-2200 4125);
PAINT MONO (-2200 4125);
DISPLAY INVISIBLE (-2200 4125);
FORCEPROP 0 LAST CDS_SEC 1
J 0
(-2200 4125);
DISPLAY 1.021277 (-2200 4125);
DISPLAY INVISIBLE (-2200 4125);
FORCEADD Q_RES..1
(-2475 4175);
FORCEPROP 1 LAST MATERIAL EMPTY
J 0
(-2125 4175);
DISPLAY 0.510638 (-2125 4175);
PAINT RED (-2125 4175);
FORCEPROP 1 LAST VALUE 10K
J 2
(-2200 4175);
DISPLAY 0.510638 (-2200 4175);
PAINT SKYBLUE (-2200 4175);
FORCEPROP 1 LAST PATH I62
J 0
(-2525 4325);
DISPLAY 0.978723 (-2525 4325);
PAINT WHITE (-2525 4325);
DISPLAY INVISIBLE (-2525 4325);
FORCEPROP 2 LAST CDS_LIB pure_quanta
J 0
(-2475 4175);
DISPLAY INVISIBLE (-2475 4175);
FORCEPROP 1 LAST PART_NUMBER TMP_QCS31002FB26
J 0
(-2500 3725);
DISPLAY 0.510638 (-2500 3725);
PAINT WHITE (-2500 3725);
DISPLAY INVISIBLE (-2500 3725);
FORCEPROP 1 LAST TOLERANCE 1%
J 0
(-2475 4075);
DISPLAY 0.510638 (-2475 4075);
PAINT SKYBLUE (-2475 4075);
DISPLAY INVISIBLE (-2475 4075);
FORCEPROP 1 LAST WATTAGE 1/16W
J 2
(-2500 4025);
DISPLAY 0.510638 (-2500 4025);
PAINT SKYBLUE (-2500 4025);
DISPLAY INVISIBLE (-2500 4025);
FORCEPROP 1 LAST PACK_TYPE 0402LF
J 0
(-2225 4025);
DISPLAY 0.510638 (-2225 4025);
PAINT SKYBLUE (-2225 4025);
DISPLAY INVISIBLE (-2225 4025);
FORCEPROP 1 LAST LOCATION R658
J 0
(-2775 4175);
DISPLAY 0.702128 (-2775 4175);
PAINT YELLOW (-2775 4175);
FORCEPROP 1 LASTPIN (-2575 4175) $PN 1
J 0
(-2563 4187);
DISPLAY 0.808511 (-2563 4187);
PAINT WHITE (-2563 4187);
FORCEPROP 1 LASTPIN (-2375 4175) $PN 2
J 0
(-2413 4187);
DISPLAY 0.808511 (-2413 4187);
PAINT WHITE (-2413 4187);
FORCEPROP 0 LAST $SEC 1
J 0
(-2200 4225);
DISPLAY 0.680851 (-2200 4225);
PAINT MONO (-2200 4225);
DISPLAY INVISIBLE (-2200 4225);
FORCEPROP 0 LAST CDS_SEC 1
J 0
(-2200 4225);
DISPLAY 1.021277 (-2200 4225);
DISPLAY INVISIBLE (-2200 4225);
FORCEADD Q_RES..1
(-2475 4225);
FORCEPROP 1 LAST MATERIAL EMPTY
J 0
(-2125 4225);
DISPLAY 0.510638 (-2125 4225);
PAINT RED (-2125 4225);
FORCEPROP 1 LAST VALUE 10K
J 2
(-2200 4225);
DISPLAY 0.510638 (-2200 4225);
PAINT SKYBLUE (-2200 4225);
FORCEPROP 1 LAST PATH I63
J 0
(-2525 4375);
DISPLAY 0.978723 (-2525 4375);
PAINT WHITE (-2525 4375);
DISPLAY INVISIBLE (-2525 4375);
FORCEPROP 2 LAST CDS_LIB pure_quanta
J 0
(-2475 4225);
DISPLAY INVISIBLE (-2475 4225);
FORCEPROP 1 LAST PART_NUMBER TMP_QCS31002FB26
J 0
(-2525 3650);
DISPLAY 0.510638 (-2525 3650);
PAINT WHITE (-2525 3650);
DISPLAY INVISIBLE (-2525 3650);
FORCEPROP 1 LAST TOLERANCE 1%
J 0
(-2475 4125);
DISPLAY 0.510638 (-2475 4125);
PAINT SKYBLUE (-2475 4125);
DISPLAY INVISIBLE (-2475 4125);
FORCEPROP 1 LAST WATTAGE 1/16W
J 2
(-2500 4075);
DISPLAY 0.510638 (-2500 4075);
PAINT SKYBLUE (-2500 4075);
DISPLAY INVISIBLE (-2500 4075);
FORCEPROP 1 LAST PACK_TYPE 0402LF
J 0
(-2225 4075);
DISPLAY 0.510638 (-2225 4075);
PAINT SKYBLUE (-2225 4075);
DISPLAY INVISIBLE (-2225 4075);
FORCEPROP 1 LAST LOCATION R657
J 0
(-2775 4225);
DISPLAY 0.702128 (-2775 4225);
PAINT YELLOW (-2775 4225);
FORCEPROP 1 LASTPIN (-2575 4225) $PN 1
J 0
(-2563 4237);
DISPLAY 0.808511 (-2563 4237);
PAINT WHITE (-2563 4237);
FORCEPROP 1 LASTPIN (-2375 4225) $PN 2
J 0
(-2413 4237);
DISPLAY 0.808511 (-2413 4237);
PAINT WHITE (-2413 4237);
FORCEPROP 0 LAST $SEC 1
J 0
(-2200 4275);
DISPLAY 0.680851 (-2200 4275);
PAINT MONO (-2200 4275);
DISPLAY INVISIBLE (-2200 4275);
FORCEPROP 0 LAST CDS_SEC 1
J 0
(-2200 4275);
DISPLAY 1.021277 (-2200 4275);
DISPLAY INVISIBLE (-2200 4275);
FORCEADD Q_RES..1
(-2475 4125);
FORCEPROP 1 LAST MATERIAL EMPTY
J 0
(-2125 4125);
DISPLAY 0.510638 (-2125 4125);
PAINT RED (-2125 4125);
FORCEPROP 1 LAST VALUE 10K
J 2
(-2200 4125);
DISPLAY 0.510638 (-2200 4125);
PAINT SKYBLUE (-2200 4125);
FORCEPROP 1 LAST PATH I64
J 0
(-2525 4275);
DISPLAY 0.978723 (-2525 4275);
PAINT WHITE (-2525 4275);
DISPLAY INVISIBLE (-2525 4275);
FORCEPROP 2 LAST CDS_LIB pure_quanta
J 0
(-2475 4125);
DISPLAY INVISIBLE (-2475 4125);
FORCEPROP 1 LAST PART_NUMBER TMP_QCS31002FB26
J 0
(-2500 3675);
DISPLAY 0.510638 (-2500 3675);
PAINT WHITE (-2500 3675);
DISPLAY INVISIBLE (-2500 3675);
FORCEPROP 1 LAST TOLERANCE 1%
J 0
(-2475 4025);
DISPLAY 0.510638 (-2475 4025);
PAINT SKYBLUE (-2475 4025);
DISPLAY INVISIBLE (-2475 4025);
FORCEPROP 1 LAST WATTAGE 1/16W
J 2
(-2500 3975);
DISPLAY 0.510638 (-2500 3975);
PAINT SKYBLUE (-2500 3975);
DISPLAY INVISIBLE (-2500 3975);
FORCEPROP 1 LAST PACK_TYPE 0402LF
J 0
(-2225 3975);
DISPLAY 0.510638 (-2225 3975);
PAINT SKYBLUE (-2225 3975);
DISPLAY INVISIBLE (-2225 3975);
FORCEPROP 1 LAST LOCATION R659
J 0
(-2775 4125);
DISPLAY 0.702128 (-2775 4125);
PAINT YELLOW (-2775 4125);
FORCEPROP 1 LASTPIN (-2575 4125) $PN 1
J 0
(-2563 4137);
DISPLAY 0.808511 (-2563 4137);
PAINT WHITE (-2563 4137);
FORCEPROP 1 LASTPIN (-2375 4125) $PN 2
J 0
(-2413 4137);
DISPLAY 0.808511 (-2413 4137);
PAINT WHITE (-2413 4137);
FORCEPROP 0 LAST $SEC 1
J 0
(-2200 4175);
DISPLAY 0.680851 (-2200 4175);
PAINT MONO (-2200 4175);
DISPLAY INVISIBLE (-2200 4175);
FORCEPROP 0 LAST CDS_SEC 1
J 0
(-2200 4175);
DISPLAY 1.021277 (-2200 4175);
DISPLAY INVISIBLE (-2200 4175);
FORCEADD Q_RES..1
(-2475 4275);
FORCEPROP 1 LAST MATERIAL EMPTY
J 0
(-2125 4275);
DISPLAY 0.510638 (-2125 4275);
PAINT RED (-2125 4275);
FORCEPROP 1 LAST VALUE 10K
J 2
(-2200 4275);
DISPLAY 0.510638 (-2200 4275);
PAINT SKYBLUE (-2200 4275);
FORCEPROP 1 LAST PATH I66
J 0
(-2525 4425);
DISPLAY 0.978723 (-2525 4425);
PAINT WHITE (-2525 4425);
DISPLAY INVISIBLE (-2525 4425);
FORCEPROP 2 LAST CDS_LIB pure_quanta
J 0
(-2475 4275);
DISPLAY INVISIBLE (-2475 4275);
FORCEPROP 1 LAST PART_NUMBER TMP_QCS31002FB26
J 0
(-2525 4375);
DISPLAY 0.510638 (-2525 4375);
PAINT WHITE (-2525 4375);
DISPLAY INVISIBLE (-2525 4375);
FORCEPROP 1 LAST TOLERANCE 1%
J 0
(-2475 4175);
DISPLAY 0.510638 (-2475 4175);
PAINT SKYBLUE (-2475 4175);
DISPLAY INVISIBLE (-2475 4175);
FORCEPROP 1 LAST WATTAGE 1/16W
J 2
(-2500 4125);
DISPLAY 0.510638 (-2500 4125);
PAINT SKYBLUE (-2500 4125);
DISPLAY INVISIBLE (-2500 4125);
FORCEPROP 1 LAST PACK_TYPE 0402LF
J 0
(-2225 4125);
DISPLAY 0.510638 (-2225 4125);
PAINT SKYBLUE (-2225 4125);
DISPLAY INVISIBLE (-2225 4125);
FORCEPROP 1 LAST LOCATION R656
J 0
(-2775 4275);
DISPLAY 0.702128 (-2775 4275);
PAINT YELLOW (-2775 4275);
FORCEPROP 1 LASTPIN (-2575 4275) $PN 1
J 0
(-2563 4287);
DISPLAY 0.808511 (-2563 4287);
PAINT WHITE (-2563 4287);
FORCEPROP 1 LASTPIN (-2375 4275) $PN 2
J 0
(-2413 4287);
DISPLAY 0.808511 (-2413 4287);
PAINT WHITE (-2413 4287);
FORCEPROP 0 LAST $SEC 1
J 0
(-2200 4325);
DISPLAY 0.680851 (-2200 4325);
PAINT MONO (-2200 4325);
DISPLAY INVISIBLE (-2200 4325);
FORCEPROP 0 LAST CDS_SEC 1
J 0
(-2200 4325);
DISPLAY 1.021277 (-2200 4325);
DISPLAY INVISIBLE (-2200 4325);
FORCEADD Q_RES..1
(-2475 4325);
FORCEPROP 1 LAST MATERIAL EMPTY
J 0
(-2125 4325);
DISPLAY 0.510638 (-2125 4325);
PAINT RED (-2125 4325);
FORCEPROP 1 LAST WATTAGE 1/16W
J 2
(-2000 4425);
DISPLAY 0.510638 (-2000 4425);
PAINT SKYBLUE (-2000 4425);
FORCEPROP 1 LAST VALUE 10K
J 2
(-2200 4325);
DISPLAY 0.510638 (-2200 4325);
PAINT SKYBLUE (-2200 4325);
FORCEPROP 1 LAST PACK_TYPE 0402LF
J 0
(-1975 4425);
DISPLAY 0.510638 (-1975 4425);
PAINT SKYBLUE (-1975 4425);
FORCEPROP 1 LAST TOLERANCE 1%
J 0
(-2375 4425);
DISPLAY 0.510638 (-2375 4425);
PAINT SKYBLUE (-2375 4425);
FORCEPROP 1 LAST PART_NUMBER TMP_QCS31002FB26
J 0
(-2600 4475);
DISPLAY 0.510638 (-2600 4475);
PAINT WHITE (-2600 4475);
FORCEPROP 1 LAST PATH I67
J 0
(-2525 4475);
DISPLAY 0.978723 (-2525 4475);
PAINT WHITE (-2525 4475);
DISPLAY INVISIBLE (-2525 4475);
FORCEPROP 2 LAST CDS_LIB pure_quanta
J 0
(-2475 4325);
DISPLAY INVISIBLE (-2475 4325);
FORCEPROP 1 LAST LOCATION R655
J 0
(-2775 4325);
DISPLAY 0.702128 (-2775 4325);
PAINT YELLOW (-2775 4325);
FORCEPROP 1 LASTPIN (-2575 4325) $PN 1
J 0
(-2563 4337);
DISPLAY 0.808511 (-2563 4337);
PAINT WHITE (-2563 4337);
FORCEPROP 1 LASTPIN (-2375 4325) $PN 2
J 0
(-2413 4337);
DISPLAY 0.808511 (-2413 4337);
PAINT WHITE (-2413 4337);
FORCEPROP 0 LAST $SEC 1
J 0
(-2500 4625);
DISPLAY 0.680851 (-2500 4625);
PAINT MONO (-2500 4625);
DISPLAY INVISIBLE (-2500 4625);
FORCEPROP 0 LAST CDS_SEC 1
J 0
(-2325 4575);
DISPLAY 1.021277 (-2325 4575);
DISPLAY INVISIBLE (-2325 4575);
FORCEADD OFFPAGE..2
(-1475 3975);
FORCEPROP 2 LAST $XR0 21 
J 0
(-1286 3975);
DISPLAY 0.638298 (-1286 3975);
PAINT MONO (-1286 3975);
FORCEPROP 2 LAST PATH I70
J 0
(-1275 4025);
DISPLAY 0.680851 (-1275 4025);
DISPLAY INVISIBLE (-1275 4025);
FORCEPROP 2 LAST CDS_LIB standard
J 0
(-1475 3975);
DISPLAY INVISIBLE (-1475 3975);
FORCEPROP 1 LAST OFFPAGE TRUE
J 0
(-1150 3850);
DISPLAY 0.872340 (-1150 3850);
PAINT GREEN (-1150 3850);
DISPLAY INVISIBLE (-1150 3850);
FORCEPROP 1 LAST COMMENT_BODY TRUE
J 0
(-1520 3880);
DISPLAY 0.872340 (-1520 3880);
PAINT PEACH (-1520 3880);
DISPLAY INVISIBLE (-1520 3880);
FORCEADD OFFPAGE..2
(-1475 3925);
FORCEPROP 2 LAST $XR0 21 
J 0
(-1286 3925);
DISPLAY 0.638298 (-1286 3925);
PAINT MONO (-1286 3925);
FORCEPROP 2 LAST PATH I71
J 0
(-1275 3975);
DISPLAY 0.680851 (-1275 3975);
DISPLAY INVISIBLE (-1275 3975);
FORCEPROP 2 LAST CDS_LIB standard
J 0
(-1475 3925);
DISPLAY INVISIBLE (-1475 3925);
FORCEPROP 1 LAST OFFPAGE TRUE
J 0
(-1150 3800);
DISPLAY 0.872340 (-1150 3800);
PAINT GREEN (-1150 3800);
DISPLAY INVISIBLE (-1150 3800);
FORCEPROP 1 LAST COMMENT_BODY TRUE
J 0
(-1520 3830);
DISPLAY 0.872340 (-1520 3830);
PAINT PEACH (-1520 3830);
DISPLAY INVISIBLE (-1520 3830);
FORCEADD OFFPAGE..2
(-1475 4025);
FORCEPROP 2 LAST $XR0 21 
J 0
(-1286 4025);
DISPLAY 0.638298 (-1286 4025);
PAINT MONO (-1286 4025);
FORCEPROP 2 LAST PATH I72
J 0
(-1275 4075);
DISPLAY 0.680851 (-1275 4075);
DISPLAY INVISIBLE (-1275 4075);
FORCEPROP 2 LAST CDS_LIB standard
J 0
(-1475 4025);
DISPLAY INVISIBLE (-1475 4025);
FORCEPROP 1 LAST OFFPAGE TRUE
J 0
(-1150 3900);
DISPLAY 0.872340 (-1150 3900);
PAINT GREEN (-1150 3900);
DISPLAY INVISIBLE (-1150 3900);
FORCEPROP 1 LAST COMMENT_BODY TRUE
J 0
(-1520 3930);
DISPLAY 0.872340 (-1520 3930);
PAINT PEACH (-1520 3930);
DISPLAY INVISIBLE (-1520 3930);
FORCEADD OFFPAGE..2
(-1475 4075);
FORCEPROP 2 LAST $XR0 21 
J 0
(-1286 4075);
DISPLAY 0.638298 (-1286 4075);
PAINT MONO (-1286 4075);
FORCEPROP 2 LAST PATH I73
J 0
(-1275 4125);
DISPLAY 0.680851 (-1275 4125);
DISPLAY INVISIBLE (-1275 4125);
FORCEPROP 2 LAST CDS_LIB standard
J 0
(-1475 4075);
DISPLAY INVISIBLE (-1475 4075);
FORCEPROP 1 LAST OFFPAGE TRUE
J 0
(-1150 3950);
DISPLAY 0.872340 (-1150 3950);
PAINT GREEN (-1150 3950);
DISPLAY INVISIBLE (-1150 3950);
FORCEPROP 1 LAST COMMENT_BODY TRUE
J 0
(-1520 3980);
DISPLAY 0.872340 (-1520 3980);
PAINT PEACH (-1520 3980);
DISPLAY INVISIBLE (-1520 3980);
FORCEADD OFFPAGE..2
(-1475 4125);
FORCEPROP 2 LAST $XR0 21 
J 0
(-1286 4125);
DISPLAY 0.638298 (-1286 4125);
PAINT MONO (-1286 4125);
FORCEPROP 2 LAST PATH I74
J 0
(-1275 4175);
DISPLAY 0.680851 (-1275 4175);
DISPLAY INVISIBLE (-1275 4175);
FORCEPROP 2 LAST CDS_LIB standard
J 0
(-1475 4125);
DISPLAY INVISIBLE (-1475 4125);
FORCEPROP 1 LAST OFFPAGE TRUE
J 0
(-1150 4000);
DISPLAY 0.872340 (-1150 4000);
PAINT GREEN (-1150 4000);
DISPLAY INVISIBLE (-1150 4000);
FORCEPROP 1 LAST COMMENT_BODY TRUE
J 0
(-1520 4030);
DISPLAY 0.872340 (-1520 4030);
PAINT PEACH (-1520 4030);
DISPLAY INVISIBLE (-1520 4030);
FORCEADD OFFPAGE..2
(-1475 4175);
FORCEPROP 2 LAST $XR0 21 
J 0
(-1286 4175);
DISPLAY 0.638298 (-1286 4175);
PAINT MONO (-1286 4175);
FORCEPROP 2 LAST PATH I75
J 0
(-1275 4225);
DISPLAY 0.680851 (-1275 4225);
DISPLAY INVISIBLE (-1275 4225);
FORCEPROP 2 LAST CDS_LIB standard
J 0
(-1475 4175);
DISPLAY INVISIBLE (-1475 4175);
FORCEPROP 1 LAST OFFPAGE TRUE
J 0
(-1150 4050);
DISPLAY 0.872340 (-1150 4050);
PAINT GREEN (-1150 4050);
DISPLAY INVISIBLE (-1150 4050);
FORCEPROP 1 LAST COMMENT_BODY TRUE
J 0
(-1520 4080);
DISPLAY 0.872340 (-1520 4080);
PAINT PEACH (-1520 4080);
DISPLAY INVISIBLE (-1520 4080);
FORCEADD OFFPAGE..2
(-1475 4225);
FORCEPROP 2 LAST $XR0 21 
J 0
(-1286 4225);
DISPLAY 0.638298 (-1286 4225);
PAINT MONO (-1286 4225);
FORCEPROP 2 LAST PATH I76
J 0
(-1275 4275);
DISPLAY 0.680851 (-1275 4275);
DISPLAY INVISIBLE (-1275 4275);
FORCEPROP 2 LAST CDS_LIB standard
J 0
(-1475 4225);
DISPLAY INVISIBLE (-1475 4225);
FORCEPROP 1 LAST OFFPAGE TRUE
J 0
(-1150 4100);
DISPLAY 0.872340 (-1150 4100);
PAINT GREEN (-1150 4100);
DISPLAY INVISIBLE (-1150 4100);
FORCEPROP 1 LAST COMMENT_BODY TRUE
J 0
(-1520 4130);
DISPLAY 0.872340 (-1520 4130);
PAINT PEACH (-1520 4130);
DISPLAY INVISIBLE (-1520 4130);
FORCEADD OFFPAGE..2
(-1475 4275);
FORCEPROP 2 LAST $XR0 21 
J 0
(-1286 4275);
DISPLAY 0.638298 (-1286 4275);
PAINT MONO (-1286 4275);
FORCEPROP 2 LAST PATH I77
J 0
(-1275 4325);
DISPLAY 0.680851 (-1275 4325);
DISPLAY INVISIBLE (-1275 4325);
FORCEPROP 2 LAST CDS_LIB standard
J 0
(-1475 4275);
DISPLAY INVISIBLE (-1475 4275);
FORCEPROP 1 LAST OFFPAGE TRUE
J 0
(-1150 4150);
DISPLAY 0.872340 (-1150 4150);
PAINT GREEN (-1150 4150);
DISPLAY INVISIBLE (-1150 4150);
FORCEPROP 1 LAST COMMENT_BODY TRUE
J 0
(-1520 4180);
DISPLAY 0.872340 (-1520 4180);
PAINT PEACH (-1520 4180);
DISPLAY INVISIBLE (-1520 4180);
FORCEADD OFFPAGE..2
(-1475 4325);
FORCEPROP 2 LAST $XR0 21 
J 0
(-1286 4325);
DISPLAY 0.638298 (-1286 4325);
PAINT MONO (-1286 4325);
FORCEPROP 2 LAST PATH I78
J 0
(-1275 4375);
DISPLAY 0.680851 (-1275 4375);
DISPLAY INVISIBLE (-1275 4375);
FORCEPROP 2 LAST CDS_LIB standard
J 0
(-1475 4325);
DISPLAY INVISIBLE (-1475 4325);
FORCEPROP 1 LAST OFFPAGE TRUE
J 0
(-1150 4200);
DISPLAY 0.872340 (-1150 4200);
PAINT GREEN (-1150 4200);
DISPLAY INVISIBLE (-1150 4200);
FORCEPROP 1 LAST COMMENT_BODY TRUE
J 0
(-1520 4230);
DISPLAY 0.872340 (-1520 4230);
PAINT PEACH (-1520 4230);
DISPLAY INVISIBLE (-1520 4230);
FORCEADD Q_CAP..1
(4500 -600);
FORCEPROP 1 LAST PACK_TYPE 0402
J 0
(4550 -750);
DISPLAY 0.510638 (4550 -750);
PAINT SKYBLUE (4550 -750);
FORCEPROP 1 LAST MATERIAL EMPTY
J 0
(4550 -700);
DISPLAY 0.510638 (4550 -700);
PAINT RED (4550 -700);
FORCEPROP 1 LAST TOLERANCE 10%
J 0
(4550 -650);
DISPLAY 0.510638 (4550 -650);
PAINT SKYBLUE (4550 -650);
FORCEPROP 1 LAST VOLTAGE 25V
J 0
(4550 -600);
DISPLAY 0.510638 (4550 -600);
PAINT SKYBLUE (4550 -600);
FORCEPROP 1 LAST PART_NUMBER CH4104K1B00
R 3
J 0
(4425 -300);
DISPLAY 0.510638 (4425 -300);
PAINT WHITE (4425 -300);
FORCEPROP 1 LAST VALUE 0.1UF
J 0
(4550 -550);
DISPLAY 0.510638 (4550 -550);
PAINT SKYBLUE (4550 -550);
FORCEPROP 1 LAST PATH I80
J 0
(4550 -450);
DISPLAY 0.978723 (4550 -450);
PAINT WHITE (4550 -450);
DISPLAY INVISIBLE (4550 -450);
FORCEPROP 2 LAST CDS_LIB pure_quanta
J 0
(4500 -600);
DISPLAY INVISIBLE (4500 -600);
FORCEPROP 1 LAST LOCATION C235
J 0
(4550 -500);
DISPLAY 0.702128 (4550 -500);
PAINT YELLOW (4550 -500);
FORCEPROP 1 LASTPIN (4500 -500) $PN 1
J 0
(4510 -520);
DISPLAY 0.808511 (4510 -520);
PAINT WHITE (4510 -520);
FORCEPROP 1 LASTPIN (4500 -700) $PN 2
J 0
(4510 -720);
DISPLAY 0.808511 (4510 -720);
PAINT WHITE (4510 -720);
FORCEPROP 0 LAST $SEC 1
J 0
(4550 -450);
DISPLAY 0.680851 (4550 -450);
PAINT MONO (4550 -450);
DISPLAY INVISIBLE (4550 -450);
FORCEPROP 0 LAST CDS_SEC 1
J 0
(4550 -450);
DISPLAY 1.021277 (4550 -450);
DISPLAY INVISIBLE (4550 -450);
FORCEADD Q_CAP..1
(4100 -600);
FORCEPROP 1 LAST PACK_TYPE C0603
J 0
(4150 -800);
DISPLAY 0.510638 (4150 -800);
PAINT SKYBLUE (4150 -800);
FORCEPROP 1 LAST VOLTAGE 10V
J 0
(4150 -600);
DISPLAY 0.510638 (4150 -600);
PAINT SKYBLUE (4150 -600);
FORCEPROP 1 LAST VALUE 22UF
J 0
(4150 -550);
DISPLAY 0.510638 (4150 -550);
PAINT SKYBLUE (4150 -550);
FORCEPROP 1 LAST PART_NUMBER CH6222M9901
J 0
(4150 -750);
DISPLAY 0.510638 (4150 -750);
PAINT WHITE (4150 -750);
FORCEPROP 1 LAST MATERIAL EMPTY
J 0
(4150 -700);
DISPLAY 0.510638 (4150 -700);
PAINT RED (4150 -700);
FORCEPROP 1 LAST TOLERANCE 20%
J 0
(4150 -650);
DISPLAY 0.510638 (4150 -650);
PAINT SKYBLUE (4150 -650);
FORCEPROP 1 LAST PATH I81
J 0
(4150 -450);
DISPLAY 0.978723 (4150 -450);
PAINT WHITE (4150 -450);
DISPLAY INVISIBLE (4150 -450);
FORCEPROP 2 LAST CDS_LIB pure_quanta
J 0
(4100 -600);
DISPLAY INVISIBLE (4100 -600);
FORCEPROP 1 LAST LOCATION C234
J 0
(4150 -500);
DISPLAY 0.702128 (4150 -500);
PAINT YELLOW (4150 -500);
FORCEPROP 1 LASTPIN (4100 -500) $PN 1
J 0
(4110 -520);
DISPLAY 0.808511 (4110 -520);
PAINT WHITE (4110 -520);
FORCEPROP 1 LASTPIN (4100 -700) $PN 2
J 0
(4110 -720);
DISPLAY 0.808511 (4110 -720);
PAINT WHITE (4110 -720);
FORCEPROP 0 LAST $SEC 1
J 0
(4150 -450);
DISPLAY 0.680851 (4150 -450);
PAINT MONO (4150 -450);
DISPLAY INVISIBLE (4150 -450);
FORCEPROP 0 LAST CDS_SEC 1
J 0
(4150 -450);
DISPLAY 0.680851 (4150 -450);
DISPLAY INVISIBLE (4150 -450);
FORCEADD SCONN67_NASA0S6730TS67..1
(1525 2575);
FORCEPROP 2 LAST VALUE SCONN67_NASA0-S6730-TS67
J 0
(1400 3900);
DISPLAY 0.680851 (1400 3900);
FORCEPROP 1 LAST PART_NUMBER DFHS75FR133
J 0
(1381 3709);
DISPLAY 0.723404 (1381 3709);
PAINT GREEN (1381 3709);
FORCEPROP 1 LAST MATERIAL IO
J 0
(1381 3582);
DISPLAY 0.723404 (1381 3582);
PAINT GREEN (1381 3582);
FORCEPROP 2 LAST PART_TYPE SMLF
J 0
(1400 3950);
DISPLAY 0.680851 (1400 3950);
FORCEPROP 2 LAST CDS_LIB pure_quanta
J 0
(1525 2575);
DISPLAY INVISIBLE (1525 2575);
FORCEPROP 1 LAST PATH I84
J 0
(1525 2575);
DISPLAY 0.723404 (1525 2575);
PAINT GREEN (1525 2575);
DISPLAY INVISIBLE (1525 2575);
FORCEPROP 1 LAST NEEDS_NO_SIZE TRUE
J 0
(1525 2575);
DISPLAY 0.723404 (1525 2575);
PAINT GREEN (1525 2575);
DISPLAY INVISIBLE (1525 2575);
FORCEPROP 1 LAST CDS_LMAN_SYM_OUTLINE -150,975,150,-975
J 0
(1525 2575);
DISPLAY 0.468085 (1525 2575);
PAINT GREEN (1525 2575);
DISPLAY INVISIBLE (1525 2575);
FORCEPROP 1 LAST $LOCATION J4
J 0
(1381 3856);
DISPLAY 0.723404 (1381 3856);
PAINT GREEN (1381 3856);
FORCEPROP 0 LASTPIN (1825 3500) $PN 1
J 0
(1835 3510);
DISPLAY 0.680851 (1835 3510);
PAINT MONO (1835 3510);
FORCEPROP 0 LASTPIN (1225 3500) $PN 2
J 2
(1215 3510);
DISPLAY 0.680851 (1215 3510);
PAINT MONO (1215 3510);
FORCEPROP 0 LASTPIN (1825 3450) $PN 3
J 0
(1835 3460);
DISPLAY 0.680851 (1835 3460);
PAINT MONO (1835 3460);
FORCEPROP 0 LASTPIN (1225 3450) $PN 4
J 2
(1215 3460);
DISPLAY 0.680851 (1215 3460);
PAINT MONO (1215 3460);
FORCEPROP 0 LASTPIN (1825 3400) $PN 5
J 0
(1835 3410);
DISPLAY 0.680851 (1835 3410);
PAINT MONO (1835 3410);
FORCEPROP 0 LASTPIN (1225 3400) $PN 6
J 2
(1215 3410);
DISPLAY 0.680851 (1215 3410);
PAINT MONO (1215 3410);
FORCEPROP 0 LASTPIN (1825 3350) $PN 7
J 0
(1835 3360);
DISPLAY 0.680851 (1835 3360);
PAINT MONO (1835 3360);
FORCEPROP 0 LASTPIN (1225 3200) $PN 16
J 2
(1215 3210);
DISPLAY 0.680851 (1215 3210);
PAINT MONO (1215 3210);
FORCEPROP 0 LASTPIN (1825 3200) $PN 17
J 0
(1835 3210);
DISPLAY 0.680851 (1835 3210);
PAINT MONO (1835 3210);
FORCEPROP 0 LASTPIN (1225 3150) $PN 18
J 2
(1215 3160);
DISPLAY 0.680851 (1215 3160);
PAINT MONO (1215 3160);
FORCEPROP 0 LASTPIN (1825 3150) $PN 19
J 0
(1835 3160);
DISPLAY 0.680851 (1835 3160);
PAINT MONO (1835 3160);
FORCEPROP 0 LASTPIN (1225 3100) $PN 20
J 2
(1215 3110);
DISPLAY 0.680851 (1215 3110);
PAINT MONO (1215 3110);
FORCEPROP 0 LASTPIN (1825 3100) $PN 21
J 0
(1835 3110);
DISPLAY 0.680851 (1835 3110);
PAINT MONO (1835 3110);
FORCEPROP 0 LASTPIN (1225 3050) $PN 22
J 2
(1215 3060);
DISPLAY 0.680851 (1215 3060);
PAINT MONO (1215 3060);
FORCEPROP 0 LASTPIN (1825 3050) $PN 23
J 0
(1835 3060);
DISPLAY 0.680851 (1835 3060);
PAINT MONO (1835 3060);
FORCEPROP 0 LASTPIN (1225 3000) $PN 24
J 2
(1215 3010);
DISPLAY 0.680851 (1215 3010);
PAINT MONO (1215 3010);
FORCEPROP 0 LASTPIN (1825 3000) $PN 25
J 0
(1835 3010);
DISPLAY 0.680851 (1835 3010);
PAINT MONO (1835 3010);
FORCEPROP 0 LASTPIN (1225 2950) $PN 26
J 2
(1215 2960);
DISPLAY 0.680851 (1215 2960);
PAINT MONO (1215 2960);
FORCEPROP 0 LASTPIN (1825 2950) $PN 27
J 0
(1835 2960);
DISPLAY 0.680851 (1835 2960);
PAINT MONO (1835 2960);
FORCEPROP 0 LASTPIN (1225 2900) $PN 28
J 2
(1215 2910);
DISPLAY 0.680851 (1215 2910);
PAINT MONO (1215 2910);
FORCEPROP 0 LASTPIN (1825 2900) $PN 29
J 0
(1835 2910);
DISPLAY 0.680851 (1835 2910);
PAINT MONO (1835 2910);
FORCEPROP 0 LASTPIN (1225 2850) $PN 30
J 2
(1215 2860);
DISPLAY 0.680851 (1215 2860);
PAINT MONO (1215 2860);
FORCEPROP 0 LASTPIN (1825 2850) $PN 31
J 0
(1835 2860);
DISPLAY 0.680851 (1835 2860);
PAINT MONO (1835 2860);
FORCEPROP 0 LASTPIN (1225 2800) $PN 32
J 2
(1215 2810);
DISPLAY 0.680851 (1215 2810);
PAINT MONO (1215 2810);
FORCEPROP 0 LASTPIN (1825 2800) $PN 33
J 0
(1835 2810);
DISPLAY 0.680851 (1835 2810);
PAINT MONO (1835 2810);
FORCEPROP 0 LASTPIN (1225 2750) $PN 34
J 2
(1215 2760);
DISPLAY 0.680851 (1215 2760);
PAINT MONO (1215 2760);
FORCEPROP 0 LASTPIN (1825 2750) $PN 35
J 0
(1835 2760);
DISPLAY 0.680851 (1835 2760);
PAINT MONO (1835 2760);
FORCEPROP 0 LASTPIN (1225 2700) $PN 36
J 2
(1215 2710);
DISPLAY 0.680851 (1215 2710);
PAINT MONO (1215 2710);
FORCEPROP 0 LASTPIN (1825 2700) $PN 37
J 0
(1835 2710);
DISPLAY 0.680851 (1835 2710);
PAINT MONO (1835 2710);
FORCEPROP 0 LASTPIN (1225 2650) $PN 38
J 2
(1215 2660);
DISPLAY 0.680851 (1215 2660);
PAINT MONO (1215 2660);
FORCEPROP 0 LASTPIN (1825 2650) $PN 39
J 0
(1835 2660);
DISPLAY 0.680851 (1835 2660);
PAINT MONO (1835 2660);
FORCEPROP 0 LASTPIN (1225 2600) $PN 40
J 2
(1215 2610);
DISPLAY 0.680851 (1215 2610);
PAINT MONO (1215 2610);
FORCEPROP 0 LASTPIN (1825 2600) $PN 41
J 0
(1835 2610);
DISPLAY 0.680851 (1835 2610);
PAINT MONO (1835 2610);
FORCEPROP 0 LASTPIN (1225 2550) $PN 42
J 2
(1215 2560);
DISPLAY 0.680851 (1215 2560);
PAINT MONO (1215 2560);
FORCEPROP 0 LASTPIN (1825 2550) $PN 43
J 0
(1835 2560);
DISPLAY 0.680851 (1835 2560);
PAINT MONO (1835 2560);
FORCEPROP 0 LASTPIN (1225 2500) $PN 44
J 2
(1215 2510);
DISPLAY 0.680851 (1215 2510);
PAINT MONO (1215 2510);
FORCEPROP 0 LASTPIN (1825 2500) $PN 45
J 0
(1835 2510);
DISPLAY 0.680851 (1835 2510);
PAINT MONO (1835 2510);
FORCEPROP 0 LASTPIN (1225 2450) $PN 46
J 2
(1215 2460);
DISPLAY 0.680851 (1215 2460);
PAINT MONO (1215 2460);
FORCEPROP 0 LASTPIN (1825 2450) $PN 47
J 0
(1835 2460);
DISPLAY 0.680851 (1835 2460);
PAINT MONO (1835 2460);
FORCEPROP 0 LASTPIN (1225 2400) $PN 48
J 2
(1215 2410);
DISPLAY 0.680851 (1215 2410);
PAINT MONO (1215 2410);
FORCEPROP 0 LASTPIN (1825 2400) $PN 49
J 0
(1835 2410);
DISPLAY 0.680851 (1835 2410);
PAINT MONO (1835 2410);
FORCEPROP 0 LASTPIN (1225 2350) $PN 50
J 2
(1215 2360);
DISPLAY 0.680851 (1215 2360);
PAINT MONO (1215 2360);
FORCEPROP 0 LASTPIN (1825 2350) $PN 51
J 0
(1835 2360);
DISPLAY 0.680851 (1835 2360);
PAINT MONO (1835 2360);
FORCEPROP 0 LASTPIN (1225 2300) $PN 52
J 2
(1215 2310);
DISPLAY 0.680851 (1215 2310);
PAINT MONO (1215 2310);
FORCEPROP 0 LASTPIN (1825 2300) $PN 53
J 0
(1835 2310);
DISPLAY 0.680851 (1835 2310);
PAINT MONO (1835 2310);
FORCEPROP 0 LASTPIN (1225 2250) $PN 54
J 2
(1215 2260);
DISPLAY 0.680851 (1215 2260);
PAINT MONO (1215 2260);
FORCEPROP 0 LASTPIN (1825 2250) $PN 55
J 0
(1835 2260);
DISPLAY 0.680851 (1835 2260);
PAINT MONO (1835 2260);
FORCEPROP 0 LASTPIN (1225 2200) $PN 56
J 2
(1215 2210);
DISPLAY 0.680851 (1215 2210);
PAINT MONO (1215 2210);
FORCEPROP 0 LASTPIN (1825 2200) $PN 57
J 0
(1835 2210);
DISPLAY 0.680851 (1835 2210);
PAINT MONO (1835 2210);
FORCEPROP 0 LASTPIN (1225 2150) $PN 58
J 2
(1215 2160);
DISPLAY 0.680851 (1215 2160);
PAINT MONO (1215 2160);
FORCEPROP 0 LASTPIN (1825 2150) $PN 59
J 0
(1835 2160);
DISPLAY 0.680851 (1835 2160);
PAINT MONO (1835 2160);
FORCEPROP 0 LASTPIN (1225 2100) $PN 60
J 2
(1215 2110);
DISPLAY 0.680851 (1215 2110);
PAINT MONO (1215 2110);
FORCEPROP 0 LASTPIN (1825 2100) $PN 61
J 0
(1835 2110);
DISPLAY 0.680851 (1835 2110);
PAINT MONO (1835 2110);
FORCEPROP 0 LASTPIN (1225 2050) $PN 62
J 2
(1215 2060);
DISPLAY 0.680851 (1215 2060);
PAINT MONO (1215 2060);
FORCEPROP 0 LASTPIN (1825 2050) $PN 63
J 0
(1835 2060);
DISPLAY 0.680851 (1835 2060);
PAINT MONO (1835 2060);
FORCEPROP 0 LASTPIN (1225 2000) $PN 64
J 2
(1215 2010);
DISPLAY 0.680851 (1215 2010);
PAINT MONO (1215 2010);
FORCEPROP 0 LASTPIN (1825 2000) $PN 65
J 0
(1835 2010);
DISPLAY 0.680851 (1835 2010);
PAINT MONO (1835 2010);
FORCEPROP 0 LASTPIN (1225 1950) $PN 66
J 2
(1215 1960);
DISPLAY 0.680851 (1215 1960);
PAINT MONO (1215 1960);
FORCEPROP 0 LASTPIN (1825 1950) $PN 67
J 0
(1835 1960);
DISPLAY 0.680851 (1835 1960);
PAINT MONO (1835 1960);
FORCEPROP 0 LASTPIN (1225 1900) $PN 68
J 2
(1215 1910);
DISPLAY 0.680851 (1215 1910);
PAINT MONO (1215 1910);
FORCEPROP 0 LASTPIN (1825 1900) $PN 69
J 0
(1835 1910);
DISPLAY 0.680851 (1835 1910);
PAINT MONO (1835 1910);
FORCEPROP 0 LASTPIN (1225 1850) $PN 70
J 2
(1215 1860);
DISPLAY 0.680851 (1215 1860);
PAINT MONO (1215 1860);
FORCEPROP 0 LASTPIN (1825 1850) $PN 71
J 0
(1835 1860);
DISPLAY 0.680851 (1835 1860);
PAINT MONO (1835 1860);
FORCEPROP 0 LASTPIN (1225 1800) $PN 72
J 2
(1215 1810);
DISPLAY 0.680851 (1215 1810);
PAINT MONO (1215 1810);
FORCEPROP 0 LASTPIN (1825 1800) $PN 73
J 0
(1835 1810);
DISPLAY 0.680851 (1835 1810);
PAINT MONO (1835 1810);
FORCEPROP 0 LASTPIN (1225 1750) $PN 74
J 2
(1215 1760);
DISPLAY 0.680851 (1215 1760);
PAINT MONO (1215 1760);
FORCEPROP 0 LASTPIN (1825 1750) $PN 75
J 0
(1835 1760);
DISPLAY 0.680851 (1835 1760);
PAINT MONO (1835 1760);
FORCEPROP 0 LASTPIN (1225 1650) $PN G1
J 2
(1215 1660);
DISPLAY 0.680851 (1215 1660);
PAINT MONO (1215 1660);
FORCEPROP 0 LASTPIN (1825 1650) $PN G2
J 0
(1835 1660);
DISPLAY 0.680851 (1835 1660);
PAINT MONO (1835 1660);
FORCEPROP 0 LAST CDS_LOCATION J4
J 0
(1400 4000);
DISPLAY 0.680851 (1400 4000);
DISPLAY INVISIBLE (1400 4000);
FORCEPROP 0 LAST $SEC 1
J 0
(1400 4000);
DISPLAY 0.680851 (1400 4000);
PAINT MONO (1400 4000);
DISPLAY INVISIBLE (1400 4000);
FORCEPROP 0 LAST CDS_SEC 1
J 0
(1400 4000);
DISPLAY 0.680851 (1400 4000);
DISPLAY INVISIBLE (1400 4000);
FORCEADD OFFPAGE..1
(-750 1275);
FORCEPROP 2 LAST $XR0 21 
J 0
(-1001 1275);
DISPLAY 0.638298 (-1001 1275);
PAINT MONO (-1001 1275);
FORCEPROP 2 LAST PATH I85
J 0
(-950 1325);
DISPLAY 0.680851 (-950 1325);
DISPLAY INVISIBLE (-950 1325);
FORCEPROP 1 LAST COMMENT_BODY TRUE
J 0
(-625 1175);
DISPLAY 0.872340 (-625 1175);
PAINT PEACH (-625 1175);
DISPLAY INVISIBLE (-625 1175);
FORCEPROP 1 LAST OFFPAGE TRUE
J 0
(-425 1150);
DISPLAY 0.872340 (-425 1150);
PAINT GREEN (-425 1150);
DISPLAY INVISIBLE (-425 1150);
FORCEPROP 2 LAST CDS_LIB standard
J 0
(-750 1275);
DISPLAY INVISIBLE (-750 1275);
FORCEADD OFFPAGE..1
(-750 1225);
FORCEPROP 2 LAST $XR0 21 
J 0
(-1001 1225);
DISPLAY 0.638298 (-1001 1225);
PAINT MONO (-1001 1225);
FORCEPROP 2 LAST PATH I86
J 0
(-950 1275);
DISPLAY 0.680851 (-950 1275);
DISPLAY INVISIBLE (-950 1275);
FORCEPROP 1 LAST COMMENT_BODY TRUE
J 0
(-625 1125);
DISPLAY 0.872340 (-625 1125);
PAINT PEACH (-625 1125);
DISPLAY INVISIBLE (-625 1125);
FORCEPROP 1 LAST OFFPAGE TRUE
J 0
(-425 1100);
DISPLAY 0.872340 (-425 1100);
PAINT GREEN (-425 1100);
DISPLAY INVISIBLE (-425 1100);
FORCEPROP 2 LAST CDS_LIB standard
J 0
(-750 1225);
DISPLAY INVISIBLE (-750 1225);
FORCEADD OFFPAGE..1
(-750 1125);
FORCEPROP 2 LAST $XR0 21 
J 0
(-1001 1125);
DISPLAY 0.638298 (-1001 1125);
PAINT MONO (-1001 1125);
FORCEPROP 2 LAST PATH I87
J 0
(-950 1175);
DISPLAY 0.680851 (-950 1175);
DISPLAY INVISIBLE (-950 1175);
FORCEPROP 1 LAST COMMENT_BODY TRUE
J 0
(-625 1025);
DISPLAY 0.872340 (-625 1025);
PAINT PEACH (-625 1025);
DISPLAY INVISIBLE (-625 1025);
FORCEPROP 1 LAST OFFPAGE TRUE
J 0
(-425 1000);
DISPLAY 0.872340 (-425 1000);
PAINT GREEN (-425 1000);
DISPLAY INVISIBLE (-425 1000);
FORCEPROP 2 LAST CDS_LIB standard
J 0
(-750 1125);
DISPLAY INVISIBLE (-750 1125);
FORCEADD OFFPAGE..1
(-750 1175);
FORCEPROP 2 LAST $XR0 21 
J 0
(-1001 1175);
DISPLAY 0.638298 (-1001 1175);
PAINT MONO (-1001 1175);
FORCEPROP 2 LAST PATH I89
J 0
(-950 1225);
DISPLAY 0.680851 (-950 1225);
DISPLAY INVISIBLE (-950 1225);
FORCEPROP 1 LAST COMMENT_BODY TRUE
J 0
(-625 1075);
DISPLAY 0.872340 (-625 1075);
PAINT PEACH (-625 1075);
DISPLAY INVISIBLE (-625 1075);
FORCEPROP 1 LAST OFFPAGE TRUE
J 0
(-425 1050);
DISPLAY 0.872340 (-425 1050);
PAINT GREEN (-425 1050);
DISPLAY INVISIBLE (-425 1050);
FORCEPROP 2 LAST CDS_LIB standard
J 0
(-750 1175);
DISPLAY INVISIBLE (-750 1175);
FORCEADD Q_RES..1
(175 2250);
FORCEPROP 1 LAST MATERIAL EMPTY
J 0
(325 2250);
DISPLAY 0.510638 (325 2250);
PAINT RED (325 2250);
FORCEPROP 1 LAST VALUE 33.2
J 2
(550 2250);
DISPLAY 0.510638 (550 2250);
PAINT SKYBLUE (550 2250);
FORCEPROP 1 LAST PATH I98
J 0
(125 2400);
DISPLAY 0.978723 (125 2400);
PAINT WHITE (125 2400);
DISPLAY INVISIBLE (125 2400);
FORCEPROP 1 LAST PACK_TYPE 0402LF
J 0
(425 2100);
DISPLAY 0.510638 (425 2100);
PAINT SKYBLUE (425 2100);
DISPLAY INVISIBLE (425 2100);
FORCEPROP 1 LAST WATTAGE 1/16W
J 2
(150 2100);
DISPLAY 0.510638 (150 2100);
PAINT SKYBLUE (150 2100);
DISPLAY INVISIBLE (150 2100);
FORCEPROP 2 LAST CDS_LIB pure_quanta
J 0
(175 2250);
DISPLAY INVISIBLE (175 2250);
FORCEPROP 1 LAST TOLERANCE 1%
J 0
(175 2150);
DISPLAY 0.510638 (175 2150);
PAINT SKYBLUE (175 2150);
DISPLAY INVISIBLE (175 2150);
FORCEPROP 1 LAST PART_NUMBER CS03322FB03
J 0
(0 2625);
DISPLAY 0.510638 (0 2625);
PAINT WHITE (0 2625);
DISPLAY INVISIBLE (0 2625);
FORCEPROP 1 LAST LOCATION R651
J 0
(-50 2250);
DISPLAY 0.702128 (-50 2250);
PAINT YELLOW (-50 2250);
FORCEPROP 1 LASTPIN (75 2250) $PN 1
J 0
(87 2262);
DISPLAY 0.808511 (87 2262);
PAINT WHITE (87 2262);
FORCEPROP 1 LASTPIN (275 2250) $PN 2
J 0
(237 2262);
DISPLAY 0.808511 (237 2262);
PAINT WHITE (237 2262);
FORCEPROP 0 LAST $SEC 1
J 0
(750 2300);
DISPLAY 0.680851 (750 2300);
PAINT MONO (750 2300);
DISPLAY INVISIBLE (750 2300);
FORCEPROP 0 LAST CDS_SEC 1
J 0
(650 2300);
DISPLAY 1.021277 (650 2300);
DISPLAY INVISIBLE (650 2300);
FORCEADD Q_RES..1
(175 2300);
FORCEPROP 1 LAST MATERIAL EMPTY
J 0
(325 2300);
DISPLAY 0.510638 (325 2300);
PAINT RED (325 2300);
FORCEPROP 1 LAST VALUE 33.2
J 2
(550 2300);
DISPLAY 0.510638 (550 2300);
PAINT SKYBLUE (550 2300);
FORCEPROP 1 LAST TOLERANCE 1%
J 0
(175 2200);
DISPLAY 0.510638 (175 2200);
PAINT SKYBLUE (175 2200);
DISPLAY INVISIBLE (175 2200);
FORCEPROP 2 LAST CDS_LIB pure_quanta
J 0
(175 2300);
DISPLAY INVISIBLE (175 2300);
FORCEPROP 1 LAST WATTAGE 1/16W
J 2
(150 2150);
DISPLAY 0.510638 (150 2150);
PAINT SKYBLUE (150 2150);
DISPLAY INVISIBLE (150 2150);
FORCEPROP 1 LAST PACK_TYPE 0402LF
J 0
(425 2150);
DISPLAY 0.510638 (425 2150);
PAINT SKYBLUE (425 2150);
DISPLAY INVISIBLE (425 2150);
FORCEPROP 1 LAST PATH I99
J 0
(125 2450);
DISPLAY 0.978723 (125 2450);
PAINT WHITE (125 2450);
DISPLAY INVISIBLE (125 2450);
FORCEPROP 1 LAST PART_NUMBER CS03322FB03
J 0
(0 2625);
DISPLAY 0.510638 (0 2625);
PAINT WHITE (0 2625);
DISPLAY INVISIBLE (0 2625);
FORCEPROP 1 LAST LOCATION R650
J 0
(-50 2300);
DISPLAY 0.702128 (-50 2300);
PAINT YELLOW (-50 2300);
FORCEPROP 1 LASTPIN (75 2300) $PN 1
J 0
(87 2312);
DISPLAY 0.808511 (87 2312);
PAINT WHITE (87 2312);
FORCEPROP 1 LASTPIN (275 2300) $PN 2
J 0
(237 2312);
DISPLAY 0.808511 (237 2312);
PAINT WHITE (237 2312);
FORCEPROP 0 LAST $SEC 1
J 0
(750 2350);
DISPLAY 0.680851 (750 2350);
PAINT MONO (750 2350);
DISPLAY INVISIBLE (750 2350);
FORCEPROP 0 LAST CDS_SEC 1
J 0
(650 2350);
DISPLAY 1.021277 (650 2350);
DISPLAY INVISIBLE (650 2350);
FORCEADD QUANTA_TITLE_BLOCK_C..1
(5925 -1775);
FORCEPROP 0 LAST CDS_CON_LAST_MODIFIED Fri Aug 25 17:25:39 2023
J 0
(4040 -1760);
DISPLAY INVISIBLE (4040 -1760);
FORCEPROP 2 LAST Q_DEPT 
J 1
(2162 -1726);
DISPLAY 1.957447 (2162 -1726);
PAINT GREEN (2162 -1726);
FORCEPROP 1 LAST CUSTOM_TXT_CDS <CON_LAST_MODIFIED>
J 0
(4040 -1760);
DISPLAY 0.978723 (4040 -1760);
FORCEPROP 2 LAST CUSTOM_TXT_CDS <XR_PAGE_TITLE>
J 0
(-1965 3475);
DISPLAY 0.638298 (-1965 3475);
PAINT PINK (-1965 3475);
DISPLAY INVISIBLE (-1965 3475);
FORCEPROP 1 LAST CUSTOM_TXT_CDS <NAME_2>
J 0
(2750 -1725);
FORCEPROP 1 LAST CUSTOM_TXT_CDS <NAME_1>
J 0
(2750 -1600);
FORCEPROP 1 LAST CUSTOM_TXT_CDS <Q_NUMBER>
J 0
(4522 -1672);
DISPLAY 1.212766 (4522 -1672);
FORCEPROP 1 LAST CUSTOM_TXT_CDS <Q_PROJ>
J 0
(3543 -1673);
DISPLAY 1.212766 (3543 -1673);
FORCEPROP 1 LAST CUSTOM_TXT_CDS <Q_REV>
J 0
(5741 -1672);
DISPLAY 1.212766 (5741 -1672);
FORCEPROP 1 LAST CUSTOM_TXT_CDS <CON_PAGE_NUM> OF <CON_TOTAL_PAGES>
J 0
(5479 -1757);
DISPLAY 0.978723 (5479 -1757);
FORCEPROP 1 LAST Q_TITLE BMC - BSM CONNECTOR
J 0
(-3441 -1749);
DISPLAY 2.446809 (-3441 -1749);
PAINT GREEN (-3441 -1749);
FORCEPROP 2 LAST CDS_XR_PAGE_TITLE CR-21 : @SCM_LIB.SCM(SCH_1):PAGE21
J 0
(-1965 3475);
DISPLAY 0.638298 (-1965 3475);
PAINT PINK (-1965 3475);
DISPLAY INVISIBLE (-1965 3475);
FORCEPROP 1 LAST COMMENT_BODY TRUE
J 0
(5937 -1788);
DISPLAY 0.978723 (5937 -1788);
PAINT PEACH (5937 -1788);
DISPLAY INVISIBLE (5937 -1788);
FORCEPROP 2 LAST PAGE_BORDER TRUE
J 0
(-1965 3475);
DISPLAY 0.638298 (-1965 3475);
PAINT PINK (-1965 3475);
DISPLAY INVISIBLE (-1965 3475);
FORCEPROP 1 LAST CDS_LMAN_SYM_OUTLINE -9475,6775,100,-125
J 0
(5925 -1775);
DISPLAY 0.468085 (5925 -1775);
PAINT GREEN (5925 -1775);
DISPLAY INVISIBLE (5925 -1775);
FORCEPROP 2 LAST CDS_LIB pure_quanta
J 0
(5925 -1775);
DISPLAY INVISIBLE (5925 -1775);
FORCEADD DNS..2
(150 3700);
PAINT RED (150 3700);
FORCEPROP 1 LAST COMMENT_BODY TRUE
R 1
J 0
(225 3475);
DISPLAY 0.872340 (225 3475);
PAINT PEACH (225 3475);
DISPLAY INVISIBLE (225 3475);
FORCEPROP 2 LAST CDS_LIB mstr_misc
J 0
(150 3700);
DISPLAY INVISIBLE (150 3700);
FORCEADD DNS..1
(-2450 4125);
PAINT RED (-2450 4125);
FORCEPROP 2 LAST CDS_LIB mstr_misc
J 0
(-2450 4125);
DISPLAY INVISIBLE (-2450 4125);
FORCEPROP 1 LAST COMMENT_BODY TRUE
R 1
J 0
(-2375 3900);
DISPLAY 0.872340 (-2375 3900);
PAINT PEACH (-2375 3900);
DISPLAY INVISIBLE (-2375 3900);
FORCEADD DNS..1
(4825 -625);
PAINT RED (4825 -625);
FORCEPROP 2 LAST CDS_LIB mstr_misc
J 0
(4825 -625);
DISPLAY INVISIBLE (4825 -625);
FORCEPROP 1 LAST COMMENT_BODY TRUE
R 1
J 0
(4900 -850);
DISPLAY 0.872340 (4900 -850);
PAINT PEACH (4900 -850);
DISPLAY INVISIBLE (4900 -850);
FORCEADD DNS..1
(4500 -625);
PAINT RED (4500 -625);
FORCEPROP 2 LAST CDS_LIB mstr_misc
J 0
(4500 -625);
DISPLAY INVISIBLE (4500 -625);
FORCEPROP 1 LAST COMMENT_BODY TRUE
R 1
J 0
(4575 -850);
DISPLAY 0.872340 (4575 -850);
PAINT PEACH (4575 -850);
DISPLAY INVISIBLE (4575 -850);
FORCEADD DNS..1
(4100 -625);
PAINT RED (4100 -625);
FORCEPROP 2 LAST CDS_LIB mstr_misc
J 0
(4100 -625);
DISPLAY INVISIBLE (4100 -625);
FORCEPROP 1 LAST COMMENT_BODY TRUE
R 1
J 0
(4175 -850);
DISPLAY 0.872340 (4175 -850);
PAINT PEACH (4175 -850);
DISPLAY INVISIBLE (4175 -850);
FORCEADD DNS..2
(175 2225);
PAINT RED (175 2225);
FORCEPROP 1 LAST COMMENT_BODY TRUE
R 1
J 0
(250 2000);
DISPLAY 0.872340 (250 2000);
PAINT PEACH (250 2000);
DISPLAY INVISIBLE (250 2000);
FORCEPROP 2 LAST CDS_LIB mstr_misc
J 0
(175 2225);
DISPLAY INVISIBLE (175 2225);
FORCEADD DNS..2
(3250 2175);
PAINT RED (3250 2175);
FORCEPROP 2 LAST CDS_LIB mstr_misc
J 0
(3250 2175);
DISPLAY INVISIBLE (3250 2175);
FORCEPROP 1 LAST COMMENT_BODY TRUE
R 1
J 0
(3325 1950);
DISPLAY 0.872340 (3325 1950);
PAINT PEACH (3325 1950);
DISPLAY INVISIBLE (3325 1950);
FORCEADD DNS..2
(3250 1925);
PAINT RED (3250 1925);
FORCEPROP 2 LAST CDS_LIB mstr_misc
J 0
(3250 1925);
DISPLAY INVISIBLE (3250 1925);
FORCEPROP 1 LAST COMMENT_BODY TRUE
R 1
J 0
(3325 1700);
DISPLAY 0.872340 (3325 1700);
PAINT PEACH (3325 1700);
DISPLAY INVISIBLE (3325 1700);
FORCEADD DNS..2
(125 2450);
PAINT RED (125 2450);
FORCEPROP 1 LAST COMMENT_BODY TRUE
R 1
J 0
(200 2225);
DISPLAY 0.872340 (200 2225);
PAINT PEACH (200 2225);
DISPLAY INVISIBLE (200 2225);
FORCEPROP 2 LAST CDS_LIB mstr_misc
J 0
(125 2450);
DISPLAY INVISIBLE (125 2450);
FORCEADD DNS..2
(4925 3625);
PAINT RED (4925 3625);
FORCEPROP 2 LAST CDS_LIB mstr_misc
J 0
(4925 3625);
DISPLAY INVISIBLE (4925 3625);
FORCEPROP 1 LAST COMMENT_BODY TRUE
R 1
J 0
(5000 3400);
DISPLAY 0.872340 (5000 3400);
PAINT PEACH (5000 3400);
DISPLAY INVISIBLE (5000 3400);
FORCEADD DNS..2
(4650 3625);
PAINT RED (4650 3625);
FORCEPROP 2 LAST CDS_LIB mstr_misc
J 0
(4650 3625);
DISPLAY INVISIBLE (4650 3625);
FORCEPROP 1 LAST COMMENT_BODY TRUE
R 1
J 0
(4725 3400);
DISPLAY 0.872340 (4725 3400);
PAINT PEACH (4725 3400);
DISPLAY INVISIBLE (4725 3400);
FORCEADD DNS..2
(3500 3175);
PAINT RED (3500 3175);
FORCEPROP 2 LAST CDS_LIB mstr_misc
J 0
(3500 3175);
DISPLAY INVISIBLE (3500 3175);
FORCEPROP 1 LAST COMMENT_BODY TRUE
R 1
J 0
(3575 2950);
DISPLAY 0.872340 (3575 2950);
PAINT PEACH (3575 2950);
DISPLAY INVISIBLE (3575 2950);
FORCEADD DNS..2
(3150 3900);
PAINT RED (3150 3900);
FORCEPROP 1 LAST COMMENT_BODY TRUE
R 1
J 0
(3225 3675);
DISPLAY 0.872340 (3225 3675);
PAINT PEACH (3225 3675);
DISPLAY INVISIBLE (3225 3675);
FORCEPROP 2 LAST CDS_LIB mstr_misc
J 0
(3150 3900);
DISPLAY INVISIBLE (3150 3900);
WIRE 16 -1 (975 3950)(975 3500);
WIRE 16 -1 (-2950 4400)(-2950 4325);
WIRE 16 -1 (500 3925)(500 3825);
WIRE 16 -1 (200 3925)(200 3900);
WIRE 16 -1 (0 2450)(-1750 2450);
WIRE 16 -1 (-2575 2450)(-2575 2350);
WIRE 16 -1 (3100 4250)(3100 4275);
WIRE 16 -1 (3100 4250)(2975 4250);
WIRE 16 -1 (3100 4025)(3100 4250);
WIRE 16 -1 (4100 25)(4100 -100);
WIRE 16 -1 (4200 -1150)(4200 -1350);
WIRE 16 -1 (4100 -1150)(4200 -1150);
WIRE 16 -1 (4500 -1150)(4200 -1150);
WIRE 16 -1 (1125 1650)(1125 950);
WIRE 16 -1 (1125 2700)(1125 1650);
WIRE 16 -1 (1125 1650)(1225 1650);
WIRE 16 -1 (1900 925)(1900 1650);
WIRE 16 -1 (4950 3450)(4950 3425);
WIRE 16 -1 (4950 3550)(4950 3450);
WIRE 16 -1 (4675 3450)(4950 3450);
WIRE 16 -1 (975 3500)(1225 3500);
WIRE 16 -1 (975 3500)(975 3450);
WIRE 16 -1 (975 3450)(1225 3450);
WIRE 16 -1 (975 1800)(1225 1800);
WIRE 16 -1 (975 3450)(975 1800);
WIRE 16 -1 (975 1800)(975 1750);
WIRE 16 -1 (975 1750)(1225 1750);
WIRE 16 -1 (4675 3550)(4675 3450);
WIRE 16 -1 (2850 4025)(2850 4250);
WIRE 16 -1 (2975 4025)(2975 4250);
WIRE 16 -1 (2850 4250)(2975 4250);
WIRE 16 -1 (1825 1650)(1900 1650);
WIRE 16 -1 (1825 1750)(1900 1750);
WIRE 16 -1 (1900 1750)(1900 1650);
WIRE 16 -1 (1825 1900)(1900 1900);
WIRE 16 -1 (1900 1900)(1900 1750);
WIRE 16 -1 (1900 2050)(1900 1900);
WIRE 16 -1 (1825 2050)(1900 2050);
WIRE 16 -1 (1900 2200)(1900 2050);
WIRE 16 -1 (1825 2200)(1900 2200);
WIRE 16 -1 (1900 2350)(1900 2200);
WIRE 16 -1 (1825 2350)(1900 2350);
WIRE 16 -1 (1900 2500)(1900 2350);
WIRE 16 -1 (1825 2500)(1900 2500);
WIRE 16 -1 (1900 2650)(1900 2500);
WIRE 16 -1 (1825 2650)(1900 2650);
WIRE 16 -1 (1900 2800)(1900 2650);
WIRE 16 -1 (1825 2800)(1900 2800);
WIRE 16 -1 (1900 2900)(1900 2800);
WIRE 16 -1 (1825 2900)(1900 2900);
WIRE 16 -1 (1900 3050)(1900 2900);
WIRE 16 -1 (1825 3050)(1900 3050);
WIRE 16 -1 (1900 3350)(1900 3050);
WIRE 16 -1 (1825 3350)(1900 3350);
WIRE 16 -1 (1900 3500)(1900 3350);
WIRE 16 -1 (1825 3500)(1900 3500);
WIRE 16 -1 (1225 3150)(1125 3150);
FORCEPROP 0 LAST VOLTAGE 0
J 0
(1175 3150);
DISPLAY INVISIBLE (1175 3150);
WIRE 16 -1 (1125 3000)(1225 3000);
WIRE 16 -1 (1125 3150)(1125 3000);
WIRE 16 -1 (1125 2850)(1225 2850);
WIRE 16 -1 (1125 3000)(1125 2850);
WIRE 16 -1 (1125 2700)(1225 2700);
WIRE 16 -1 (1125 2850)(1125 2700);
WIRE 16 -1 (4775 -700)(4775 -1150);
WIRE 16 -1 (4775 -1150)(4500 -1150);
WIRE 16 -1 (4500 -700)(4500 -1150);
WIRE 16 -1 (4100 -700)(4100 -1150);
WIRE 16 -1 (4775 -100)(4775 -500);
WIRE 16 -1 (4500 -100)(4500 -500);
WIRE 16 -1 (4500 -100)(4775 -100);
WIRE 16 -1 (4100 -100)(4100 -500);
WIRE 16 -1 (4500 -100)(4100 -100);
WIRE 16 -1 (225 3825)(225 3900);
WIRE 16 -1 (50 3900)(50 3825);
WIRE 16 -1 (225 3900)(200 3900);
WIRE 16 -1 (200 3900)(50 3900);
WIRE 16 -1 (-2575 4325)(-2950 4325);
WIRE 16 -1 (-2950 4325)(-2950 4275);
WIRE 16 -1 (-2575 4275)(-2950 4275);
WIRE 16 -1 (-2950 4275)(-2950 4225);
WIRE 16 -1 (-2575 4225)(-2950 4225);
WIRE 16 -1 (-2950 4225)(-2950 4175);
WIRE 16 -1 (-2575 4175)(-2950 4175);
WIRE 16 -1 (-2950 4175)(-2950 4125);
WIRE 16 -1 (-2575 4125)(-2950 4125);
WIRE 16 -1 (-2575 4075)(-2950 4075);
WIRE 16 -1 (-2950 4125)(-2950 4075);
WIRE 16 -1 (-2950 4075)(-2950 4025);
WIRE 16 -1 (-2575 4025)(-2950 4025);
WIRE 16 -1 (-2950 4025)(-2950 3975);
WIRE 16 -1 (-2575 3975)(-2950 3975);
WIRE 16 -1 (-2950 3975)(-2950 3925);
WIRE 16 -1 (-2575 3925)(-2950 3925);
WIRE 16 -1 (50 2900)(50 3625);
WIRE 16 -1 (50 2900)(1225 2900);
FORCEPROP 2 LAST SIG_NAME SPI_BMC_HOLD0_N
J 0
(240 2910);
DISPLAY 0.851064 (240 2910);
WIRE 16 -1 (1225 2550)(200 2550);
FORCEPROP 2 LAST SIG_NAME SMB_BMC_MM16_R1_SDA
J 0
(415 2560);
DISPLAY 0.808511 (415 2560);
WIRE 16 -1 (1225 2450)(200 2450);
FORCEPROP 2 LAST SIG_NAME EMMC_WP
J 0
(590 2460);
DISPLAY 0.808511 (590 2460);
WIRE 16 -1 (275 2250)(550 2250);
WIRE 16 -1 (1225 2250)(550 2250);
FORCEPROP 2 LAST SIG_NAME EMMC_DT6_R
J 2
(965 2260);
DISPLAY 0.808511 (965 2260);
WIRE 16 -1 (550 1175)(550 2250);
WIRE 16 -1 (-700 1175)(550 1175);
WIRE 16 -1 (275 2200)(575 2200);
WIRE 16 -1 (1225 2200)(575 2200);
FORCEPROP 2 LAST SIG_NAME EMMC_DT5_R
J 2
(965 2210);
DISPLAY 0.808511 (965 2210);
WIRE 16 -1 (575 1225)(575 2200);
WIRE 16 -1 (-700 1225)(575 1225);
WIRE 16 -1 (2650 1400)(2475 1400);
WIRE 16 -1 (2650 2000)(1825 2000);
FORCEPROP 2 LAST SIG_NAME EMMC_DT2_R
J 0
(1965 2010);
DISPLAY 0.808511 (1965 2010);
WIRE 16 -1 (3150 2000)(2650 2000);
WIRE 16 -1 (2650 2000)(2650 1400);
WIRE 16 -1 (2475 1350)(2700 1350);
WIRE 16 -1 (2700 1950)(1825 1950);
FORCEPROP 2 LAST SIG_NAME EMMC_DT1_R
J 0
(1965 1960);
DISPLAY 0.808511 (1965 1960);
WIRE 16 -1 (2700 1350)(2700 1950);
WIRE 16 -1 (3150 1950)(2700 1950);
WIRE 16 -1 (2750 1850)(1825 1850);
FORCEPROP 2 LAST SIG_NAME EMMC_DT0_R
J 0
(1965 1860);
DISPLAY 0.808511 (1965 1860);
WIRE 16 -1 (3150 1850)(2750 1850);
WIRE 16 -1 (2750 1300)(2750 1850);
WIRE 16 -1 (2475 1300)(2750 1300);
WIRE 16 -1 (1225 1950)(-600 1950);
FORCEPROP 2 LAST SIG_NAME BMC_EMMC_RST_N
J 0
(-610 1960);
DISPLAY 0.808511 (-610 1960);
WIRE 16 -1 (275 2150)(600 2150);
WIRE 16 -1 (1225 2150)(600 2150);
FORCEPROP 2 LAST SIG_NAME EMMC_DT4_R
J 2
(965 2160);
DISPLAY 0.808511 (965 2160);
WIRE 16 -1 (600 1275)(600 2150);
WIRE 16 -1 (-700 1275)(600 1275);
WIRE 16 -1 (-1525 4075)(-2375 4075);
FORCEPROP 2 LAST SIG_NAME EMMC_DT5_R
J 0
(-1960 4085);
DISPLAY 0.808511 (-1960 4085);
WIRE 16 -1 (-1525 4225)(-2375 4225);
FORCEPROP 2 LAST SIG_NAME EMMC_DT2_R
J 0
(-1960 4235);
DISPLAY 0.808511 (-1960 4235);
WIRE 16 2175 (-2325 3875)(-2325 4400);
WIRE 16 2175 (-2800 3875)(-2325 3875);
WIRE 16 2175 (-2325 4400)(-2800 4400);
WIRE 16 2175 (-2800 4400)(-2800 3875);
WIRE 16 -1 (-1525 4175)(-2375 4175);
FORCEPROP 2 LAST SIG_NAME EMMC_DT3_R
J 0
(-1960 4185);
DISPLAY 0.808511 (-1960 4185);
WIRE 16 -1 (-1525 4125)(-2375 4125);
FORCEPROP 2 LAST SIG_NAME EMMC_DT4_R
J 0
(-1960 4135);
DISPLAY 0.808511 (-1960 4135);
WIRE 16 273 (5850 550)(5850 4600);
WIRE 16 273 (-1200 4600)(5850 4600);
WIRE 16 273 (-1200 550)(-1200 4600);
WIRE 16 -1 (-1525 4275)(-2375 4275);
FORCEPROP 2 LAST SIG_NAME EMMC_DT1_R
J 0
(-1960 4285);
DISPLAY 0.808511 (-1960 4285);
WIRE 16 -1 (-1525 4325)(-2375 4325);
FORCEPROP 2 LAST SIG_NAME EMMC_DT0_R
J 0
(-1960 4335);
DISPLAY 0.808511 (-1960 4335);
WIRE 16 -1 (-1525 4025)(-2375 4025);
FORCEPROP 2 LAST SIG_NAME EMMC_DT6_R
J 0
(-1960 4035);
DISPLAY 0.808511 (-1960 4035);
WIRE 16 -1 (500 3625)(500 3200);
WIRE 16 -1 (500 3200)(1225 3200);
FORCEPROP 2 LAST SIG_NAME BSM_PRSNT_N
J 0
(540 3210);
DISPLAY 0.808511 (540 3210);
WIRE 16 -1 (-50 3200)(500 3200);
WIRE 16 -1 (225 2950)(225 3625);
FORCEPROP 2 LAST SIG_NAME SPI_BMC_HOLD1_N
J 0
(240 2960);
DISPLAY 0.851064 (240 2960);
WIRE 16 -1 (225 2950)(1225 2950);
WIRE 16 -1 (1225 2600)(200 2600);
FORCEPROP 2 LAST SIG_NAME SMB_BMC_MM16_R1_SCL
J 0
(415 2610);
DISPLAY 0.808511 (415 2610);
WIRE 16 -1 (75 2150)(-600 2150);
FORCEPROP 2 LAST SIG_NAME BMC_EMMC_DT4
J 0
(-585 2160);
DISPLAY 0.808511 (-585 2160);
WIRE 16 -1 (75 2200)(-600 2200);
FORCEPROP 2 LAST SIG_NAME BMC_EMMC_DT5
J 0
(-585 2210);
DISPLAY 0.808511 (-585 2210);
WIRE 16 -1 (75 2250)(-600 2250);
FORCEPROP 2 LAST SIG_NAME BMC_EMMC_DT6
J 0
(-585 2260);
DISPLAY 0.808511 (-585 2260);
WIRE 16 -1 (75 2300)(-600 2300);
FORCEPROP 2 LAST SIG_NAME BMC_EMMC_DT7
J 0
(-585 2310);
DISPLAY 0.808511 (-585 2310);
WIRE 16 -1 (0 2550)(-950 2550);
FORCEPROP 2 LAST SIG_NAME SMB_BMC_MM16_R5_SDA
J 0
(-950 2560);
DISPLAY 0.808511 (-950 2560);
WIRE 16 -1 (0 2600)(-950 2600);
FORCEPROP 2 LAST SIG_NAME SMB_BMC_MM16_R5_SCL
J 0
(-950 2610);
DISPLAY 0.808511 (-950 2610);
WIRE 16 -1 (2550 1500)(2475 1500);
WIRE 16 -1 (3150 2150)(2550 2150);
WIRE 16 -1 (1825 2150)(2550 2150);
FORCEPROP 2 LAST SIG_NAME EMMC_CMD_R
J 0
(1965 2160);
DISPLAY 0.808511 (1965 2160);
WIRE 16 -1 (2550 2150)(2550 1500);
WIRE 16 -1 (2600 1450)(2475 1450);
WIRE 16 -1 (3150 2100)(2600 2100);
WIRE 16 -1 (1825 2100)(2600 2100);
FORCEPROP 2 LAST SIG_NAME EMMC_DT3_R
J 0
(1965 2110);
DISPLAY 0.808511 (1965 2110);
WIRE 16 -1 (2600 2100)(2600 1450);
WIRE 16 -1 (1825 2750)(2850 2750);
FORCEPROP 2 LAST SIG_NAME SPI_BMC_CS1_FLASH_R_N
J 0
(1965 2760);
DISPLAY 0.808511 (1965 2760);
WIRE 16 -1 (3400 2750)(2850 2750);
WIRE 16 -1 (2850 3825)(2850 2750);
WIRE 16 -1 (1825 3150)(3100 3150);
FORCEPROP 2 LAST SIG_NAME RST_SPI_BMC_FLASH_R2_N
J 0
(1965 3160);
DISPLAY 0.808511 (1965 3160);
WIRE 16 -1 (3100 3150)(3400 3150);
WIRE 16 -1 (3100 3825)(3100 3150);
WIRE 16 -1 (4650 3000)(3600 3000);
FORCEPROP 2 LAST SIG_NAME SPI_BMC_BOOT_MISO
J 2
(4665 3010);
DISPLAY 0.808511 (4665 3010);
WIRE 16 -1 (3600 2950)(4650 2950);
FORCEPROP 2 LAST SIG_NAME SPI_BMC_BOOT_MOSI
J 2
(4665 2960);
DISPLAY 0.808511 (4665 2960);
WIRE 16 -1 (3600 2850)(4650 2850);
FORCEPROP 2 LAST SIG_NAME SPI_BMC_BOOT_CLK
J 2
(4640 2860);
DISPLAY 0.808511 (4640 2860);
WIRE 16 -1 (3600 2750)(4650 2750);
FORCEPROP 2 LAST SIG_NAME SPI_BMC_BOOT_CS1_R_N
J 2
(4665 2760);
DISPLAY 0.808511 (4665 2760);
WIRE 16 -1 (3600 2700)(4650 2700);
FORCEPROP 2 LAST SIG_NAME SPI_BMC_BOOT_CS0_R_N
J 2
(4665 2710);
DISPLAY 0.808511 (4665 2710);
WIRE 16 -1 (275 2300)(525 2300);
WIRE 16 -1 (1225 2300)(525 2300);
FORCEPROP 2 LAST SIG_NAME EMMC_DT7_R
J 2
(965 2310);
DISPLAY 0.808511 (965 2310);
WIRE 16 -1 (525 1125)(525 2300);
WIRE 16 -1 (-700 1125)(525 1125);
WIRE 16 -1 (4950 3750)(4950 3925);
WIRE 16 -1 (4950 3925)(5500 3925);
FORCEPROP 2 LAST SIG_NAME SPI_BMC_BT_WP0_N_R
J 2
(5375 3935);
DISPLAY 0.808511 (5375 3935);
WIRE 16 -1 (4150 3925)(4950 3925);
WIRE 16 -1 (4150 3400)(4150 3925);
WIRE 16 -1 (1825 3400)(4150 3400);
WIRE 16 -1 (1825 3100)(3400 3100);
FORCEPROP 2 LAST SIG_NAME RST_SPI_BMC_FLASH_R1_N
J 0
(1965 3110);
DISPLAY 0.808511 (1965 3110);
WIRE 16 -1 (3400 3000)(1825 3000);
FORCEPROP 2 LAST SIG_NAME SPI_BMC_IO1_FLASH_R
J 0
(1965 3010);
DISPLAY 0.808511 (1965 3010);
WIRE 16 -1 (3400 2950)(1825 2950);
FORCEPROP 2 LAST SIG_NAME SPI_BMC_IO0_FLASH_R
J 0
(1965 2960);
DISPLAY 0.808511 (1965 2960);
WIRE 16 -1 (1825 2850)(3400 2850);
FORCEPROP 2 LAST SIG_NAME SPI_BMC_CLK_FLASH_R
J 0
(1965 2860);
DISPLAY 0.808511 (1965 2860);
WIRE 16 -1 (1825 2700)(2975 2700);
FORCEPROP 2 LAST SIG_NAME SPI_BMC_CS0_FLASH_R_N
J 0
(1965 2710);
DISPLAY 0.808511 (1965 2710);
WIRE 16 -1 (2975 2700)(3400 2700);
WIRE 16 -1 (2975 3825)(2975 2700);
WIRE 16 -1 (4275 2250)(3350 2250);
FORCEPROP 2 LAST SIG_NAME BMC_EMMC_CLK
J 2
(4190 2250);
DISPLAY 0.808511 (4190 2250);
WIRE 16 -1 (3350 2150)(4275 2150);
FORCEPROP 2 LAST SIG_NAME BMC_EMMC_CMD
J 2
(4190 2160);
DISPLAY 0.808511 (4190 2160);
WIRE 16 -1 (3350 2100)(4275 2100);
FORCEPROP 2 LAST SIG_NAME BMC_EMMC_DT3
J 2
(4190 2110);
DISPLAY 0.808511 (4190 2110);
WIRE 16 -1 (3350 1950)(4275 1950);
FORCEPROP 2 LAST SIG_NAME BMC_EMMC_DT1
J 2
(4190 1960);
DISPLAY 0.808511 (4190 1960);
WIRE 16 -1 (3350 1850)(4275 1850);
FORCEPROP 2 LAST SIG_NAME BMC_EMMC_DT0
J 2
(4190 1860);
DISPLAY 0.808511 (4190 1860);
WIRE 16 -1 (3350 2000)(4275 2000);
FORCEPROP 2 LAST SIG_NAME BMC_EMMC_DT2
J 2
(4190 2010);
DISPLAY 0.808511 (4190 2010);
WIRE 16 -1 (3150 2250)(1825 2250);
FORCEPROP 2 LAST SIG_NAME EMMC_CLK_R
J 0
(1965 2260);
DISPLAY 0.808511 (1965 2260);
WIRE 16 273 (-1100 525)(5850 525);
WIRE 16 -1 (5500 3975)(4675 3975);
FORCEPROP 2 LAST SIG_NAME SPI_BMC_BT_WP1_N_R
J 2
(5375 3985);
DISPLAY 0.808511 (5375 3985);
WIRE 16 -1 (4675 3750)(4675 3975);
WIRE 16 -1 (4100 3450)(1825 3450);
WIRE 16 -1 (4675 3975)(4100 3975);
WIRE 16 -1 (4100 3975)(4100 3450);
WIRE 16 -1 (4650 3100)(3600 3100);
FORCEPROP 2 LAST SIG_NAME RST_SPI_FLASH_BUF_N
J 0
(3940 3110);
DISPLAY 0.808511 (3940 3110);
WIRE 16 -1 (3600 3150)(4650 3150);
FORCEPROP 2 LAST SIG_NAME RST_SPI_FLASH_BUF_N
J 0
(3940 3160);
DISPLAY 0.808511 (3940 3160);
WIRE 16 -1 (-2575 1950)(-2700 1950);
WIRE 16 -1 (-2575 2150)(-2575 1950);
WIRE 16 -1 (-1700 1950)(-2575 1950);
FORCEPROP 2 LAST SIG_NAME BMC_EMMC_RST_N
J 0
(-2435 1960);
DISPLAY 0.808511 (-2435 1960);
WIRE 16 -1 (-925 3200)(-250 3200);
FORCEPROP 2 LAST SIG_NAME BSM_PRSNT_R_N
J 0
(-935 3210);
DISPLAY 0.808511 (-935 3210);
WIRE 16 -1 (-1525 3925)(-2375 3925);
FORCEPROP 2 LAST SIG_NAME EMMC_CMD_R
J 0
(-1960 3935);
DISPLAY 0.808511 (-1960 3935);
WIRE 16 -1 (-1525 3975)(-2375 3975);
FORCEPROP 2 LAST SIG_NAME EMMC_DT7_R
J 0
(-1960 3985);
DISPLAY 0.808511 (-1960 3985);
DOT 1 (200 3900);
DOT 1 (2600 2100);
DOT 1 (2850 2750);
DOT 1 (2975 2700);
DOT 1 (4500 -100);
DOT 1 (1900 2050);
DOT 1 (1900 2200);
DOT 1 (-2575 1950);
DOT 1 (-2950 4325);
DOT 1 (1900 2650);
DOT 1 (1125 2850);
DOT 1 (975 3450);
DOT 1 (1900 1750);
DOT 1 (1900 2350);
DOT 1 (-2950 4125);
DOT 1 (1900 3050);
DOT 1 (1900 2900);
DOT 1 (1900 2800);
DOT 1 (1900 1900);
DOT 1 (1900 1650);
DOT 1 (975 1800);
DOT 1 (1125 1650);
DOT 1 (4200 -1150);
DOT 1 (4500 -1150);
DOT 1 (4100 -100);
DOT 1 (-2950 4025);
DOT 1 (-2950 3975);
DOT 1 (-2950 4075);
DOT 1 (-2950 4225);
DOT 1 (-2950 4275);
DOT 1 (-2950 4175);
DOT 1 (1900 2500);
DOT 1 (1125 2700);
DOT 1 (4950 3450);
DOT 1 (4675 3975);
DOT 1 (4950 3925);
DOT 1 (3100 3150);
DOT 1 (3100 4250);
DOT 1 (2975 4250);
DOT 1 (1900 3350);
DOT 1 (2650 2000);
DOT 1 (2550 2150);
DOT 1 (2750 1850);
DOT 1 (975 3500);
DOT 1 (500 3200);
DOT 1 (2700 1950);
DOT 1 (1125 3000);
DOT 1 (525 2300);
DOT 1 (550 2250);
DOT 1 (575 2200);
DOT 1 (600 2150);
FORCENOTE
MOVE BMC FLASH TO BSM_20220214
(-1100 4650) 0;
DISPLAY LEFT (-1100 4650);
DISPLAY 1.021277 (-1100 4650);
QUIT
